FILE_TYPE = MACRO_DRAWING;
SET COLOR_WIRE YELLOW;
SET COLOR_PROP ORANGE;
SET COLOR_DOT WHITE;
SET COLOR_ARC YELLOW;
SET COLOR_BODY GREEN;
SET COLOR_NOTE PURPLE;
SET PROP_DISPLAY VALUE;
SET PAGE_NUMBER P360;
FORCEADD Q_RES..2
(525 350);
FORCEPROP 1 LAST LOCATION R3620
J 0
(600 425);
DISPLAY 0.638298 (600 425);
FORCEPROP 0 LAST $SEC 1
J 0
(600 475);
DISPLAY 0.680851 (600 475);
PAINT MONO (600 475);
DISPLAY INVISIBLE (600 475);
FORCEPROP 0 LAST CDS_SEC 1
J 0
(600 475);
DISPLAY 1.021277 (600 475);
DISPLAY INVISIBLE (600 475);
FORCEPROP 1 LASTPIN (525 450) $PN 1
J 0
(530 412);
DISPLAY 0.787234 (530 412);
PAINT MONO (530 412);
FORCEPROP 1 LASTPIN (525 250) $PN 2
J 0
(530 260);
DISPLAY 0.787234 (530 260);
PAINT MONO (530 260);
FORCEPROP 1 LAST TOLERANCE 5%
J 0
(600 375);
DISPLAY 0.404255 (600 375);
FORCEPROP 1 LAST PACK_TYPE 0402LF
J 0
(600 275);
DISPLAY 0.404255 (600 275);
FORCEPROP 1 LAST VALUE 0
J 0
(600 400);
DISPLAY 0.404255 (600 400);
FORCEPROP 1 LAST WATTAGE 1/16W
J 0
(600 350);
DISPLAY 0.404255 (600 350);
FORCEPROP 1 LAST MATERIAL CHIP
J 0
(600 325);
DISPLAY 0.404255 (600 325);
FORCEPROP 2 LAST CDS_LIB pure_quanta
J 0
(525 350);
DISPLAY INVISIBLE (525 350);
FORCEPROP 1 LAST PATH I100
J 0
(575 525);
DISPLAY 0.978723 (575 525);
PAINT WHITE (575 525);
DISPLAY INVISIBLE (575 525);
FORCEPROP 1 LAST PART_NUMBER CS00002JB13
J 0
(600 300);
DISPLAY 0.404255 (600 300);
DISPLAY INVISIBLE (600 300);
FORCEADD Q_RES..1
(-525 600);
FORCEPROP 1 LAST LOCATION R3608
J 0
(-650 600);
DISPLAY 0.638298 (-650 600);
FORCEPROP 0 LAST $SEC 1
J 0
(-650 650);
DISPLAY 0.680851 (-650 650);
PAINT MONO (-650 650);
DISPLAY INVISIBLE (-650 650);
FORCEPROP 0 LAST CDS_SEC 1
J 0
(-650 650);
DISPLAY 1.021277 (-650 650);
DISPLAY INVISIBLE (-650 650);
FORCEPROP 1 LASTPIN (-625 600) $PN 1
J 0
(-613 612);
DISPLAY 0.787234 (-613 612);
PAINT MONO (-613 612);
FORCEPROP 1 LASTPIN (-425 600) $PN 2
J 0
(-463 612);
DISPLAY 0.787234 (-463 612);
PAINT MONO (-463 612);
FORCEPROP 1 LAST PACK_TYPE 0402LF
J 0
(-50 600);
DISPLAY 0.510638 (-50 600);
FORCEPROP 1 LAST MATERIAL CHIP
J 0
(-150 600);
DISPLAY 0.510638 (-150 600);
FORCEPROP 1 LAST WATTAGE 1/16W
J 2
(-200 600);
DISPLAY 0.510638 (-200 600);
FORCEPROP 1 LAST VALUE 4.7K
J 2
(-325 600);
DISPLAY 0.510638 (-325 600);
FORCEPROP 1 LAST TOLERANCE 1%
J 0
(-200 600);
DISPLAY 0.510638 (-200 600);
FORCEPROP 2 LAST CDS_LIB pure_quanta
J 0
(-525 600);
DISPLAY INVISIBLE (-525 600);
FORCEPROP 1 LAST PATH I103
J 0
(-575 750);
DISPLAY 0.978723 (-575 750);
PAINT WHITE (-575 750);
DISPLAY INVISIBLE (-575 750);
FORCEPROP 1 LAST PART_NUMBER CS24702FB06
J 0
(-950 600);
DISPLAY 0.510638 (-950 600);
DISPLAY INVISIBLE (-950 600);
FORCEADD Q_RES..1
(-525 525);
FORCEPROP 1 LAST LOCATION R3609
J 0
(-650 525);
DISPLAY 0.638298 (-650 525);
FORCEPROP 0 LAST $SEC 1
J 0
(-650 575);
DISPLAY 0.680851 (-650 575);
PAINT MONO (-650 575);
DISPLAY INVISIBLE (-650 575);
FORCEPROP 0 LAST CDS_SEC 1
J 0
(-650 575);
DISPLAY 1.021277 (-650 575);
DISPLAY INVISIBLE (-650 575);
FORCEPROP 1 LASTPIN (-625 525) $PN 1
J 0
(-613 537);
DISPLAY 0.787234 (-613 537);
PAINT MONO (-613 537);
FORCEPROP 1 LASTPIN (-425 525) $PN 2
J 0
(-463 537);
DISPLAY 0.787234 (-463 537);
PAINT MONO (-463 537);
FORCEPROP 1 LAST PACK_TYPE 0402LF
J 0
(-50 525);
DISPLAY 0.510638 (-50 525);
FORCEPROP 1 LAST WATTAGE 1/16W
J 2
(-200 525);
DISPLAY 0.510638 (-200 525);
FORCEPROP 1 LAST VALUE 4.7K
J 2
(-325 525);
DISPLAY 0.510638 (-325 525);
FORCEPROP 1 LAST MATERIAL EMPTY
J 0
(-150 525);
DISPLAY 0.510638 (-150 525);
PAINT RED (-150 525);
FORCEPROP 1 LAST TOLERANCE 1%
J 0
(-200 525);
DISPLAY 0.510638 (-200 525);
FORCEPROP 2 LAST CDS_LIB pure_quanta
J 0
(-525 525);
DISPLAY INVISIBLE (-525 525);
FORCEPROP 1 LAST PATH I104
J 0
(-575 675);
DISPLAY 0.978723 (-575 675);
PAINT WHITE (-575 675);
DISPLAY INVISIBLE (-575 675);
FORCEPROP 1 LAST PART_NUMBER CS24702FB06
J 0
(-950 525);
DISPLAY 0.510638 (-950 525);
DISPLAY INVISIBLE (-950 525);
FORCEADD UNIVERSAL_GND..1
(-950 400);
FORCEPROP 3 LASTPIN (-950 450) SIG_NAME GND\g
J 0
(-940 460);
DISPLAY 0.659574 (-940 460);
PAINT MONO (-940 460);
DISPLAY INVISIBLE (-940 460);
FORCEPROP 2 LAST CDS_LIB pure_quanta_power
J 0
(-950 400);
DISPLAY INVISIBLE (-950 400);
FORCEPROP 1 LAST HDL_POWER GND
J 1
(-925 325);
DISPLAY 0.872340 (-925 325);
PAINT GREEN (-925 325);
DISPLAY INVISIBLE (-925 325);
FORCEPROP 1 LAST PATH I105
J 0
(-875 400);
DISPLAY 0.872340 (-875 400);
PAINT AQUA (-875 400);
DISPLAY INVISIBLE (-875 400);
FORCEADD OFFPAGE..1
(-1075 125);
FORCEPROP 2 LAST $XR0 252 
J 0
(-1357 125);
DISPLAY 0.638298 (-1357 125);
PAINT MONO (-1357 125);
FORCEPROP 2 LAST CDS_LIB standard
J 0
(-1075 125);
DISPLAY INVISIBLE (-1075 125);
FORCEPROP 1 LAST OFFPAGE TRUE
J 0
(-750 0);
DISPLAY 0.872340 (-750 0);
DISPLAY INVISIBLE (-750 0);
FORCEPROP 1 LAST COMMENT_BODY TRUE
J 0
(-950 25);
DISPLAY 0.872340 (-950 25);
PAINT GREEN (-950 25);
DISPLAY INVISIBLE (-950 25);
FORCEPROP 2 LAST PATH I106
J 0
(-1325 175);
DISPLAY 1.021277 (-1325 175);
DISPLAY INVISIBLE (-1325 175);
FORCEADD UNIVERSAL_GND..1
(2350 -525);
FORCEPROP 3 LASTPIN (2350 -475) SIG_NAME GND\g
J 0
(2360 -465);
DISPLAY 0.659574 (2360 -465);
PAINT MONO (2360 -465);
DISPLAY INVISIBLE (2360 -465);
FORCEPROP 2 LAST CDS_LIB pure_quanta_power
J 0
(2350 -525);
DISPLAY INVISIBLE (2350 -525);
FORCEPROP 1 LAST HDL_POWER GND
J 1
(2375 -600);
DISPLAY 0.872340 (2375 -600);
PAINT GREEN (2375 -600);
DISPLAY INVISIBLE (2375 -600);
FORCEPROP 1 LAST PATH I107
J 0
(2425 -525);
DISPLAY 0.872340 (2425 -525);
PAINT AQUA (2425 -525);
DISPLAY INVISIBLE (2425 -525);
FORCEADD Q_CAP..1
(500 -625);
FORCEPROP 1 LAST LOCATION C2020
J 0
(550 -525);
DISPLAY 0.978723 (550 -525);
FORCEPROP 0 LAST $SEC 1
J 0
(550 -475);
DISPLAY 0.680851 (550 -475);
PAINT MONO (550 -475);
DISPLAY INVISIBLE (550 -475);
FORCEPROP 0 LAST CDS_SEC 1
J 0
(550 -475);
DISPLAY 1.021277 (550 -475);
DISPLAY INVISIBLE (550 -475);
FORCEPROP 1 LASTPIN (500 -525) $PN 1
J 0
(510 -545);
DISPLAY 0.787234 (510 -545);
PAINT MONO (510 -545);
FORCEPROP 1 LASTPIN (500 -725) $PN 2
J 0
(510 -745);
DISPLAY 0.787234 (510 -745);
PAINT MONO (510 -745);
FORCEPROP 1 LAST PACK_TYPE 0402
J 0
(550 -700);
DISPLAY 0.510638 (550 -700);
FORCEPROP 1 LAST MATERIAL X7R
J 0
(550 -650);
DISPLAY 0.510638 (550 -650);
FORCEPROP 1 LAST VOLTAGE 25V
J 0
(550 -600);
DISPLAY 0.510638 (550 -600);
FORCEPROP 1 LAST VALUE 0.1UF
J 0
(550 -575);
DISPLAY 0.510638 (550 -575);
FORCEPROP 1 LAST TOLERANCE 10%
J 0
(550 -625);
DISPLAY 0.510638 (550 -625);
FORCEPROP 2 LAST CDS_LIB pure_quanta
J 0
(500 -625);
DISPLAY INVISIBLE (500 -625);
FORCEPROP 1 LAST PATH I108
J 0
(550 -475);
DISPLAY 0.978723 (550 -475);
PAINT WHITE (550 -475);
DISPLAY INVISIBLE (550 -475);
FORCEPROP 1 LAST PART_NUMBER CH4104K1B00
J 0
(550 -675);
DISPLAY 0.510638 (550 -675);
DISPLAY INVISIBLE (550 -675);
FORCEADD Q_RES..1
(150 -475);
FORCEPROP 1 LAST LOCATION R3570
J 0
(-100 -475);
DISPLAY 0.638298 (-100 -475);
FORCEPROP 0 LAST $SEC 1
J 0
(0 -375);
DISPLAY 0.680851 (0 -375);
PAINT MONO (0 -375);
DISPLAY INVISIBLE (0 -375);
FORCEPROP 0 LAST CDS_SEC 1
J 0
(0 -375);
DISPLAY 1.021277 (0 -375);
DISPLAY INVISIBLE (0 -375);
FORCEPROP 1 LASTPIN (50 -475) $PN 1
J 0
(62 -463);
DISPLAY 0.787234 (62 -463);
PAINT MONO (62 -463);
FORCEPROP 1 LASTPIN (250 -475) $PN 2
J 0
(212 -463);
DISPLAY 0.787234 (212 -463);
PAINT MONO (212 -463);
FORCEPROP 1 LAST MATERIAL CHIP
J 0
(175 -575);
DISPLAY 0.638298 (175 -575);
FORCEPROP 1 LAST TOLERANCE 1%
J 0
(200 -525);
DISPLAY 0.638298 (200 -525);
FORCEPROP 1 LAST VALUE 10
J 2
(100 -525);
DISPLAY 0.638298 (100 -525);
FORCEPROP 1 LAST WATTAGE 1/16W
J 2
(150 -575);
DISPLAY 0.638298 (150 -575);
FORCEPROP 1 LAST PACK_TYPE 0402LF
J 0
(275 -525);
DISPLAY 0.638298 (275 -525);
FORCEPROP 2 LAST CDS_LIB pure_quanta
J 0
(150 -475);
DISPLAY INVISIBLE (150 -475);
FORCEPROP 1 LAST PATH I109
J 0
(100 -325);
DISPLAY 0.978723 (100 -325);
PAINT WHITE (100 -325);
DISPLAY INVISIBLE (100 -325);
FORCEPROP 1 LAST PART_NUMBER CS01002FB07
J 0
(0 -425);
DISPLAY 0.638298 (0 -425);
DISPLAY INVISIBLE (0 -425);
FORCEADD Q_RES..1
(150 -750);
FORCEPROP 1 LAST LOCATION R3571
J 0
(-100 -750);
DISPLAY 0.638298 (-100 -750);
FORCEPROP 0 LAST $SEC 1
J 0
(0 -650);
DISPLAY 0.680851 (0 -650);
PAINT MONO (0 -650);
DISPLAY INVISIBLE (0 -650);
FORCEPROP 0 LAST CDS_SEC 1
J 0
(0 -650);
DISPLAY 1.021277 (0 -650);
DISPLAY INVISIBLE (0 -650);
FORCEPROP 1 LASTPIN (50 -750) $PN 1
J 0
(62 -738);
DISPLAY 0.787234 (62 -738);
PAINT MONO (62 -738);
FORCEPROP 1 LASTPIN (250 -750) $PN 2
J 0
(212 -738);
DISPLAY 0.787234 (212 -738);
PAINT MONO (212 -738);
FORCEPROP 1 LAST PACK_TYPE 0402LF
J 0
(275 -800);
DISPLAY 0.638298 (275 -800);
FORCEPROP 1 LAST WATTAGE 1/16W
J 2
(150 -850);
DISPLAY 0.638298 (150 -850);
FORCEPROP 1 LAST TOLERANCE 1%
J 0
(200 -800);
DISPLAY 0.638298 (200 -800);
FORCEPROP 1 LAST VALUE 10
J 2
(100 -800);
DISPLAY 0.638298 (100 -800);
FORCEPROP 1 LAST MATERIAL CHIP
J 0
(175 -850);
DISPLAY 0.638298 (175 -850);
FORCEPROP 2 LAST CDS_LIB pure_quanta
J 0
(150 -750);
DISPLAY INVISIBLE (150 -750);
FORCEPROP 1 LAST PATH I110
J 0
(100 -600);
DISPLAY 0.978723 (100 -600);
PAINT WHITE (100 -600);
DISPLAY INVISIBLE (100 -600);
FORCEPROP 1 LAST PART_NUMBER CS01002FB07
J 0
(0 -700);
DISPLAY 0.638298 (0 -700);
DISPLAY INVISIBLE (0 -700);
FORCEADD OFFPAGE..3
R 2
(-1075 75);
FORCEPROP 2 LAST $XR0 252 
J 0
(-1355 75);
DISPLAY 0.638298 (-1355 75);
PAINT MONO (-1355 75);
FORCEPROP 2 LAST CDS_LIB standard
J 2
(-1075 75);
PAINT MONO (-1075 75);
DISPLAY INVISIBLE (-1075 75);
FORCEPROP 1 LAST OFFPAGE TRUE
J 2
(-1400 -50);
DISPLAY 0.872340 (-1400 -50);
DISPLAY INVISIBLE (-1400 -50);
FORCEPROP 1 LAST COMMENT_BODY TRUE
J 2
(-1025 -25);
DISPLAY 0.872340 (-1025 -25);
PAINT GREEN (-1025 -25);
DISPLAY INVISIBLE (-1025 -25);
FORCEPROP 2 LAST PATH I111
J 0
(-1350 125);
DISPLAY 1.021277 (-1350 125);
DISPLAY INVISIBLE (-1350 125);
FORCEADD UNIVERSAL_POWER..1
(-1250 -125);
FORCEPROP 3 LASTPIN (-1250 -175) SIG_NAME P3V3_OCP_V3_2_R\g
J 0
(-1240 -165);
DISPLAY 0.659574 (-1240 -165);
PAINT MONO (-1240 -165);
DISPLAY INVISIBLE (-1240 -165);
FORCEPROP 1 LAST HDL_POWER P3V3_OCP_V3_2_R
J 1
(-1250 -75);
DISPLAY 0.872340 (-1250 -75);
PAINT GREEN (-1250 -75);
FORCEPROP 2 LAST CDS_LIB pure_quanta_power
J 0
(-1250 -125);
DISPLAY INVISIBLE (-1250 -125);
FORCEPROP 1 LAST PATH I112
J 0
(-1200 -100);
DISPLAY 0.872340 (-1200 -100);
PAINT AQUA (-1200 -100);
DISPLAY INVISIBLE (-1200 -100);
FORCEADD UNIVERSAL_POWER..1
(-1400 625);
FORCEPROP 3 LASTPIN (-1400 575) SIG_NAME P3V3_OCP_V3_2_R\g
J 0
(-1390 585);
DISPLAY 0.659574 (-1390 585);
PAINT MONO (-1390 585);
DISPLAY INVISIBLE (-1390 585);
FORCEPROP 1 LAST HDL_POWER P3V3_OCP_V3_2_R
J 1
(-1400 675);
DISPLAY 0.872340 (-1400 675);
PAINT GREEN (-1400 675);
FORCEPROP 2 LAST CDS_LIB pure_quanta_power
J 0
(-1400 625);
DISPLAY INVISIBLE (-1400 625);
FORCEPROP 1 LAST PATH I113
J 0
(-1350 650);
DISPLAY 0.872340 (-1350 650);
PAINT AQUA (-1350 650);
DISPLAY INVISIBLE (-1350 650);
FORCEADD Q_CAP..1
(-1650 300);
FORCEPROP 1 LAST LOCATION C2017
J 0
(-1600 400);
DISPLAY 0.978723 (-1600 400);
FORCEPROP 0 LAST $SEC 1
J 0
(-1600 450);
DISPLAY 0.680851 (-1600 450);
PAINT MONO (-1600 450);
DISPLAY INVISIBLE (-1600 450);
FORCEPROP 0 LAST CDS_SEC 1
J 0
(-1600 450);
DISPLAY 1.021277 (-1600 450);
DISPLAY INVISIBLE (-1600 450);
FORCEPROP 1 LASTPIN (-1650 400) $PN 1
J 0
(-1640 380);
DISPLAY 0.787234 (-1640 380);
PAINT MONO (-1640 380);
FORCEPROP 1 LASTPIN (-1650 200) $PN 2
J 0
(-1640 180);
DISPLAY 0.787234 (-1640 180);
PAINT MONO (-1640 180);
FORCEPROP 1 LAST VALUE 0.1UF
J 0
(-1600 350);
DISPLAY 0.638298 (-1600 350);
FORCEPROP 1 LAST VOLTAGE 25V
J 0
(-1600 300);
DISPLAY 0.638298 (-1600 300);
FORCEPROP 1 LAST TOLERANCE 10%
J 0
(-1600 250);
DISPLAY 0.638298 (-1600 250);
FORCEPROP 1 LAST PACK_TYPE 0402
J 0
(-1600 150);
DISPLAY 0.638298 (-1600 150);
FORCEPROP 1 LAST MATERIAL X7R
J 0
(-1600 200);
DISPLAY 0.638298 (-1600 200);
FORCEPROP 2 LAST CDS_LIB pure_quanta
J 0
(-1650 300);
DISPLAY INVISIBLE (-1650 300);
FORCEPROP 1 LAST PATH I114
J 0
(-1600 450);
DISPLAY 0.978723 (-1600 450);
PAINT WHITE (-1600 450);
DISPLAY INVISIBLE (-1600 450);
FORCEPROP 1 LAST PART_NUMBER CH4104K1B00
J 0
(-1600 150);
DISPLAY 0.808511 (-1600 150);
DISPLAY INVISIBLE (-1600 150);
FORCEADD UNIVERSAL_GND..1
(-1650 25);
FORCEPROP 3 LASTPIN (-1650 75) SIG_NAME GND\g
J 0
(-1640 85);
DISPLAY 0.659574 (-1640 85);
PAINT MONO (-1640 85);
DISPLAY INVISIBLE (-1640 85);
FORCEPROP 2 LAST CDS_LIB pure_quanta_power
J 0
(-1650 25);
DISPLAY INVISIBLE (-1650 25);
FORCEPROP 1 LAST HDL_POWER GND
J 1
(-1625 -50);
DISPLAY 0.872340 (-1625 -50);
PAINT GREEN (-1625 -50);
DISPLAY INVISIBLE (-1625 -50);
FORCEPROP 1 LAST PATH I115
J 0
(-1575 25);
DISPLAY 0.872340 (-1575 25);
PAINT AQUA (-1575 25);
DISPLAY INVISIBLE (-1575 25);
FORCEADD Q_RES..1
(-1750 -275);
FORCEPROP 1 LAST LOCATION R3633
J 0
(-1800 -225);
DISPLAY 0.978723 (-1800 -225);
FORCEPROP 0 LAST $SEC 1
J 0
(-1800 -175);
DISPLAY 0.680851 (-1800 -175);
PAINT MONO (-1800 -175);
DISPLAY INVISIBLE (-1800 -175);
FORCEPROP 0 LAST CDS_SEC 1
J 0
(-1800 -175);
DISPLAY 1.021277 (-1800 -175);
DISPLAY INVISIBLE (-1800 -175);
FORCEPROP 1 LASTPIN (-1850 -275) $PN 1
J 0
(-1838 -263);
DISPLAY 0.787234 (-1838 -263);
PAINT MONO (-1838 -263);
FORCEPROP 1 LASTPIN (-1650 -275) $PN 2
J 0
(-1688 -263);
DISPLAY 0.787234 (-1688 -263);
PAINT MONO (-1688 -263);
FORCEPROP 1 LAST PACK_TYPE 2512LF
J 0
(-1675 -375);
DISPLAY 0.510638 (-1675 -375);
FORCEPROP 1 LAST MATERIAL CHIP
J 0
(-1750 -425);
DISPLAY 0.510638 (-1750 -425);
FORCEPROP 1 LAST VALUE 0.002
J 2
(-1775 -375);
DISPLAY 0.510638 (-1775 -375);
FORCEPROP 1 LAST TOLERANCE 1%
J 0
(-1750 -375);
DISPLAY 0.510638 (-1750 -375);
FORCEPROP 1 LAST WATTAGE 2W
J 2
(-1775 -425);
DISPLAY 0.510638 (-1775 -425);
FORCEPROP 2 LAST CDS_LIB pure_quanta
J 0
(-1750 -275);
DISPLAY INVISIBLE (-1750 -275);
FORCEPROP 1 LAST PATH I116
J 0
(-1800 -125);
DISPLAY 0.978723 (-1800 -125);
PAINT WHITE (-1800 -125);
DISPLAY INVISIBLE (-1800 -125);
FORCEPROP 1 LAST PART_NUMBER CS+002AFR06
J 0
(-1875 -325);
DISPLAY 0.510638 (-1875 -325);
DISPLAY INVISIBLE (-1875 -325);
FORCEADD UNIVERSAL_POWER..1
(-2325 -125);
FORCEPROP 3 LASTPIN (-2325 -175) SIG_NAME P3V3_OCP_V3_2\g
J 0
(-2315 -165);
DISPLAY 0.659574 (-2315 -165);
PAINT MONO (-2315 -165);
DISPLAY INVISIBLE (-2315 -165);
FORCEPROP 1 LAST HDL_POWER P3V3_OCP_V3_2
J 1
(-2325 -75);
DISPLAY 0.872340 (-2325 -75);
PAINT GREEN (-2325 -75);
FORCEPROP 2 LAST CDS_LIB pure_quanta_power
J 0
(-2325 -125);
DISPLAY INVISIBLE (-2325 -125);
FORCEPROP 1 LAST PATH I117
J 0
(-2275 -100);
DISPLAY 0.872340 (-2275 -100);
PAINT AQUA (-2275 -100);
DISPLAY INVISIBLE (-2275 -100);
FORCEADD UNIVERSAL_POWER..1
(-2625 -4375);
FORCEPROP 3 LASTPIN (-2625 -4425) SIG_NAME P12V_SCM\g
J 0
(-2615 -4415);
DISPLAY 0.659574 (-2615 -4415);
PAINT MONO (-2615 -4415);
DISPLAY INVISIBLE (-2615 -4415);
FORCEPROP 1 LAST HDL_POWER P12V_SCM
J 1
(-2625 -4325);
DISPLAY 0.872340 (-2625 -4325);
PAINT GREEN (-2625 -4325);
FORCEPROP 2 LAST CDS_LIB pure_quanta_power
J 0
(-2625 -4375);
DISPLAY INVISIBLE (-2625 -4375);
FORCEPROP 1 LAST PATH I118
J 0
(-2575 -4350);
DISPLAY 0.872340 (-2575 -4350);
PAINT AQUA (-2575 -4350);
DISPLAY INVISIBLE (-2575 -4350);
FORCEADD UNIVERSAL_POWER..1
(-1550 -4375);
FORCEPROP 3 LASTPIN (-1550 -4425) SIG_NAME P12V_SCM_R\g
J 0
(-1540 -4415);
DISPLAY 0.659574 (-1540 -4415);
PAINT MONO (-1540 -4415);
DISPLAY INVISIBLE (-1540 -4415);
FORCEPROP 1 LAST HDL_POWER P12V_SCM_R
J 1
(-1550 -4325);
DISPLAY 0.872340 (-1550 -4325);
PAINT GREEN (-1550 -4325);
FORCEPROP 2 LAST CDS_LIB pure_quanta_power
J 0
(-1550 -4375);
DISPLAY INVISIBLE (-1550 -4375);
FORCEPROP 1 LAST PATH I119
J 0
(-1500 -4350);
DISPLAY 0.872340 (-1500 -4350);
PAINT AQUA (-1500 -4350);
DISPLAY INVISIBLE (-1500 -4350);
FORCEADD UNIVERSAL_POWER..1
(-1700 -3625);
FORCEPROP 3 LASTPIN (-1700 -3675) SIG_NAME P12V_SCM_R\g
J 0
(-1690 -3665);
DISPLAY 0.659574 (-1690 -3665);
PAINT MONO (-1690 -3665);
DISPLAY INVISIBLE (-1690 -3665);
FORCEPROP 1 LAST HDL_POWER P12V_SCM_R
J 1
(-1700 -3575);
DISPLAY 0.872340 (-1700 -3575);
PAINT GREEN (-1700 -3575);
FORCEPROP 2 LAST CDS_LIB pure_quanta_power
J 0
(-1700 -3625);
DISPLAY INVISIBLE (-1700 -3625);
FORCEPROP 1 LAST PATH I120
J 0
(-1650 -3600);
DISPLAY 0.872340 (-1650 -3600);
PAINT AQUA (-1650 -3600);
DISPLAY INVISIBLE (-1650 -3600);
FORCEADD UNIVERSAL_POWER..1
(2675 -3225);
FORCEPROP 3 LASTPIN (2675 -3275) SIG_NAME P3V3_AUX\g
J 0
(2685 -3265);
DISPLAY 0.659574 (2685 -3265);
PAINT MONO (2685 -3265);
DISPLAY INVISIBLE (2685 -3265);
FORCEPROP 1 LAST HDL_POWER P3V3_AUX
J 1
(2675 -3175);
DISPLAY 0.872340 (2675 -3175);
PAINT GREEN (2675 -3175);
FORCEPROP 2 LAST CDS_LIB pure_quanta_power
J 0
(2675 -3225);
DISPLAY INVISIBLE (2675 -3225);
FORCEPROP 1 LAST PATH I121
J 0
(2725 -3200);
DISPLAY 0.872340 (2725 -3200);
PAINT AQUA (2725 -3200);
DISPLAY INVISIBLE (2725 -3200);
FORCEADD Q_RES..2
(2675 -3425);
FORCEPROP 1 LAST LOCATION R4091
J 0
(2720 -3300);
DISPLAY 0.978723 (2720 -3300);
FORCEPROP 0 LAST $SEC 1
J 0
(2725 -3250);
DISPLAY 0.680851 (2725 -3250);
PAINT MONO (2725 -3250);
DISPLAY INVISIBLE (2725 -3250);
FORCEPROP 0 LAST CDS_SEC 1
J 0
(2725 -3250);
DISPLAY 1.021277 (2725 -3250);
DISPLAY INVISIBLE (2725 -3250);
FORCEPROP 1 LASTPIN (2675 -3325) $PN 1
J 0
(2680 -3363);
DISPLAY 0.787234 (2680 -3363);
PAINT MONO (2680 -3363);
FORCEPROP 1 LASTPIN (2675 -3525) $PN 2
J 0
(2680 -3515);
DISPLAY 0.787234 (2680 -3515);
PAINT MONO (2680 -3515);
FORCEPROP 1 LAST MATERIAL CHIP
J 0
(2715 -3500);
DISPLAY 0.787234 (2715 -3500);
FORCEPROP 1 LAST WATTAGE 1/16W
J 0
(2715 -3450);
DISPLAY 0.787234 (2715 -3450);
FORCEPROP 1 LAST TOLERANCE 1%
J 0
(2720 -3400);
DISPLAY 0.787234 (2720 -3400);
FORCEPROP 1 LAST PACK_TYPE 0402LF
J 0
(2715 -3600);
DISPLAY 0.787234 (2715 -3600);
FORCEPROP 1 LAST VALUE 1K
J 0
(2720 -3350);
DISPLAY 0.787234 (2720 -3350);
FORCEPROP 2 LAST CDS_LIB pure_quanta
J 0
(2675 -3425);
DISPLAY INVISIBLE (2675 -3425);
FORCEPROP 1 LAST PATH I122
J 0
(2725 -3250);
DISPLAY 0.978723 (2725 -3250);
PAINT WHITE (2725 -3250);
DISPLAY INVISIBLE (2725 -3250);
FORCEPROP 1 LAST PART_NUMBER CS21002FB06
J 0
(2715 -3550);
DISPLAY 0.787234 (2715 -3550);
DISPLAY INVISIBLE (2715 -3550);
FORCEADD UNIVERSAL_POWER..1
(2600 -1075);
FORCEPROP 3 LASTPIN (2600 -1125) SIG_NAME P3V3_AUX\g
J 0
(2610 -1115);
DISPLAY 0.659574 (2610 -1115);
PAINT MONO (2610 -1115);
DISPLAY INVISIBLE (2610 -1115);
FORCEPROP 1 LAST HDL_POWER P3V3_AUX
J 1
(2600 -1025);
DISPLAY 0.872340 (2600 -1025);
PAINT GREEN (2600 -1025);
FORCEPROP 2 LAST CDS_LIB pure_quanta_power
J 0
(2600 -1075);
DISPLAY INVISIBLE (2600 -1075);
FORCEPROP 1 LAST PATH I123
J 0
(2650 -1050);
DISPLAY 0.872340 (2650 -1050);
PAINT AQUA (2650 -1050);
DISPLAY INVISIBLE (2650 -1050);
FORCEADD Q_RES..2
(2600 -1275);
FORCEPROP 1 LAST LOCATION R4090
J 0
(2645 -1150);
DISPLAY 0.978723 (2645 -1150);
FORCEPROP 0 LAST $SEC 1
J 0
(2650 -1100);
DISPLAY 0.680851 (2650 -1100);
PAINT MONO (2650 -1100);
DISPLAY INVISIBLE (2650 -1100);
FORCEPROP 0 LAST CDS_SEC 1
J 0
(2650 -1100);
DISPLAY 1.021277 (2650 -1100);
DISPLAY INVISIBLE (2650 -1100);
FORCEPROP 1 LASTPIN (2600 -1175) $PN 1
J 0
(2605 -1213);
DISPLAY 0.787234 (2605 -1213);
PAINT MONO (2605 -1213);
FORCEPROP 1 LASTPIN (2600 -1375) $PN 2
J 0
(2605 -1365);
DISPLAY 0.787234 (2605 -1365);
PAINT MONO (2605 -1365);
FORCEPROP 1 LAST MATERIAL CHIP
J 0
(2640 -1350);
DISPLAY 0.787234 (2640 -1350);
FORCEPROP 1 LAST PACK_TYPE 0402LF
J 0
(2640 -1450);
DISPLAY 0.787234 (2640 -1450);
FORCEPROP 1 LAST TOLERANCE 1%
J 0
(2645 -1250);
DISPLAY 0.787234 (2645 -1250);
FORCEPROP 1 LAST WATTAGE 1/16W
J 0
(2640 -1300);
DISPLAY 0.787234 (2640 -1300);
FORCEPROP 1 LAST VALUE 1K
J 0
(2645 -1200);
DISPLAY 0.787234 (2645 -1200);
FORCEPROP 2 LAST CDS_LIB pure_quanta
J 0
(2600 -1275);
DISPLAY INVISIBLE (2600 -1275);
FORCEPROP 1 LAST PATH I124
J 0
(2650 -1100);
DISPLAY 0.978723 (2650 -1100);
PAINT WHITE (2650 -1100);
DISPLAY INVISIBLE (2650 -1100);
FORCEPROP 1 LAST PART_NUMBER CS21002FB06
J 0
(2640 -1400);
DISPLAY 0.787234 (2640 -1400);
DISPLAY INVISIBLE (2640 -1400);
FORCEADD UNIVERSAL_POWER..1
(3175 1025);
FORCEPROP 3 LASTPIN (3175 975) SIG_NAME P3V3_AUX\g
J 0
(3185 985);
DISPLAY 0.659574 (3185 985);
PAINT MONO (3185 985);
DISPLAY INVISIBLE (3185 985);
FORCEPROP 1 LAST HDL_POWER P3V3_AUX
J 1
(3175 1075);
DISPLAY 0.872340 (3175 1075);
PAINT GREEN (3175 1075);
FORCEPROP 2 LAST CDS_LIB pure_quanta_power
J 0
(3175 1025);
DISPLAY INVISIBLE (3175 1025);
FORCEPROP 1 LAST PATH I125
J 0
(3225 1050);
DISPLAY 0.872340 (3225 1050);
PAINT AQUA (3225 1050);
DISPLAY INVISIBLE (3225 1050);
FORCEADD Q_RES..2
(3175 825);
FORCEPROP 1 LAST LOCATION R4092
J 0
(3220 950);
DISPLAY 0.978723 (3220 950);
FORCEPROP 0 LAST $SEC 1
J 0
(3225 1000);
DISPLAY 0.680851 (3225 1000);
PAINT MONO (3225 1000);
DISPLAY INVISIBLE (3225 1000);
FORCEPROP 0 LAST CDS_SEC 1
J 0
(3225 1000);
DISPLAY 1.021277 (3225 1000);
DISPLAY INVISIBLE (3225 1000);
FORCEPROP 1 LASTPIN (3175 925) $PN 1
J 0
(3180 887);
DISPLAY 0.787234 (3180 887);
PAINT MONO (3180 887);
FORCEPROP 1 LASTPIN (3175 725) $PN 2
J 0
(3180 735);
DISPLAY 0.787234 (3180 735);
PAINT MONO (3180 735);
FORCEPROP 1 LAST MATERIAL CHIP
J 0
(3215 750);
DISPLAY 0.787234 (3215 750);
FORCEPROP 1 LAST WATTAGE 1/16W
J 0
(3215 800);
DISPLAY 0.787234 (3215 800);
FORCEPROP 1 LAST PACK_TYPE 0402LF
J 0
(3215 650);
DISPLAY 0.787234 (3215 650);
FORCEPROP 1 LAST TOLERANCE 1%
J 0
(3220 850);
DISPLAY 0.787234 (3220 850);
FORCEPROP 1 LAST VALUE 1K
J 0
(3220 900);
DISPLAY 0.787234 (3220 900);
FORCEPROP 2 LAST CDS_LIB pure_quanta
J 0
(3175 825);
DISPLAY INVISIBLE (3175 825);
FORCEPROP 1 LAST PATH I126
J 0
(3225 1000);
DISPLAY 0.978723 (3225 1000);
PAINT WHITE (3225 1000);
DISPLAY INVISIBLE (3225 1000);
FORCEPROP 1 LAST PART_NUMBER CS21002FB06
J 0
(3215 700);
DISPLAY 0.787234 (3215 700);
DISPLAY INVISIBLE (3215 700);
FORCEADD Q_RES..1
(100 75);
FORCEPROP 1 LAST LOCATION R3569
J 0
(-175 75);
DISPLAY 0.787234 (-175 75);
FORCEPROP 0 LAST $SEC 1
J 0
(400 125);
DISPLAY 0.680851 (400 125);
PAINT MONO (400 125);
DISPLAY INVISIBLE (400 125);
FORCEPROP 0 LAST CDS_SEC 1
J 0
(400 125);
DISPLAY 0.680851 (400 125);
DISPLAY INVISIBLE (400 125);
FORCEPROP 1 LASTPIN (0 75) $PN 1
J 0
(12 87);
DISPLAY 0.787234 (12 87);
PAINT MONO (12 87);
FORCEPROP 1 LASTPIN (200 75) $PN 2
J 0
(162 87);
DISPLAY 0.787234 (162 87);
PAINT MONO (162 87);
FORCEPROP 1 LAST VALUE 0
J 2
(275 75);
DISPLAY 0.638298 (275 75);
FORCEPROP 1 LAST TOLERANCE 5%
J 0
(300 75);
DISPLAY 0.638298 (300 75);
FORCEPROP 1 LAST MATERIAL CHIP
J 0
(400 75);
DISPLAY 0.638298 (400 75);
FORCEPROP 2 LAST CDS_LIB pure_quanta
J 0
(100 75);
DISPLAY INVISIBLE (100 75);
FORCEPROP 1 LAST PACK_TYPE 0402LF
J 0
(0 150);
DISPLAY 0.404255 (0 150);
DISPLAY INVISIBLE (0 150);
FORCEPROP 1 LAST WATTAGE 1/16W
J 2
(275 150);
DISPLAY 0.510638 (275 150);
DISPLAY INVISIBLE (275 150);
FORCEPROP 1 LAST PATH I127
J 0
(50 225);
DISPLAY 0.978723 (50 225);
PAINT WHITE (50 225);
DISPLAY INVISIBLE (50 225);
FORCEPROP 1 LAST PART_NUMBER CS00002JB13
J 0
(0 125);
DISPLAY 0.404255 (0 125);
DISPLAY INVISIBLE (0 125);
FORCEADD Q_RES..1
(100 125);
FORCEPROP 1 LAST LOCATION R3568
J 0
(-175 125);
DISPLAY 0.787234 (-175 125);
FORCEPROP 0 LAST $SEC 1
J 0
(275 225);
DISPLAY 0.680851 (275 225);
PAINT MONO (275 225);
DISPLAY INVISIBLE (275 225);
FORCEPROP 0 LAST CDS_SEC 1
J 0
(275 225);
DISPLAY 0.680851 (275 225);
DISPLAY INVISIBLE (275 225);
FORCEPROP 1 LASTPIN (0 125) $PN 1
J 0
(12 137);
DISPLAY 0.787234 (12 137);
PAINT MONO (12 137);
FORCEPROP 1 LASTPIN (200 125) $PN 2
J 0
(162 137);
DISPLAY 0.787234 (162 137);
PAINT MONO (162 137);
FORCEPROP 1 LAST TOLERANCE 5%
J 0
(300 125);
DISPLAY 0.638298 (300 125);
FORCEPROP 1 LAST PACK_TYPE 0402LF
J 0
(0 200);
DISPLAY 0.404255 (0 200);
FORCEPROP 1 LAST VALUE 0
J 2
(275 125);
DISPLAY 0.638298 (275 125);
FORCEPROP 1 LAST WATTAGE 1/16W
J 2
(275 200);
DISPLAY 0.510638 (275 200);
FORCEPROP 1 LAST MATERIAL CHIP
J 0
(400 125);
DISPLAY 0.638298 (400 125);
FORCEPROP 2 LAST CDS_LIB pure_quanta
J 0
(100 125);
DISPLAY INVISIBLE (100 125);
FORCEPROP 1 LAST PATH I128
J 0
(50 275);
DISPLAY 0.978723 (50 275);
PAINT WHITE (50 275);
DISPLAY INVISIBLE (50 275);
FORCEPROP 1 LAST PART_NUMBER CS00002JB13
J 0
(0 175);
DISPLAY 0.404255 (0 175);
DISPLAY INVISIBLE (0 175);
FORCEADD Q_RES..1
(-300 -2025);
FORCEPROP 1 LAST LOCATION R3573
J 0
(-575 -2025);
DISPLAY 0.787234 (-575 -2025);
FORCEPROP 0 LAST $SEC 1
J 0
(0 -1975);
DISPLAY 0.680851 (0 -1975);
PAINT MONO (0 -1975);
DISPLAY INVISIBLE (0 -1975);
FORCEPROP 0 LAST CDS_SEC 1
J 0
(0 -1975);
DISPLAY 0.680851 (0 -1975);
DISPLAY INVISIBLE (0 -1975);
FORCEPROP 1 LASTPIN (-400 -2025) $PN 1
J 0
(-388 -2013);
DISPLAY 0.787234 (-388 -2013);
PAINT MONO (-388 -2013);
FORCEPROP 1 LASTPIN (-200 -2025) $PN 2
J 0
(-238 -2013);
DISPLAY 0.787234 (-238 -2013);
PAINT MONO (-238 -2013);
FORCEPROP 1 LAST TOLERANCE 5%
J 0
(-100 -2025);
DISPLAY 0.638298 (-100 -2025);
FORCEPROP 1 LAST MATERIAL CHIP
J 0
(0 -2025);
DISPLAY 0.638298 (0 -2025);
FORCEPROP 1 LAST VALUE 0
J 2
(-125 -2025);
DISPLAY 0.638298 (-125 -2025);
FORCEPROP 1 LAST WATTAGE 1/16W
J 2
(-125 -1950);
DISPLAY 0.510638 (-125 -1950);
DISPLAY INVISIBLE (-125 -1950);
FORCEPROP 1 LAST PACK_TYPE 0402LF
J 0
(-400 -1950);
DISPLAY 0.404255 (-400 -1950);
DISPLAY INVISIBLE (-400 -1950);
FORCEPROP 2 LAST CDS_LIB pure_quanta
J 0
(-300 -2025);
DISPLAY INVISIBLE (-300 -2025);
FORCEPROP 1 LAST PATH I129
J 0
(-350 -1875);
DISPLAY 0.978723 (-350 -1875);
PAINT WHITE (-350 -1875);
DISPLAY INVISIBLE (-350 -1875);
FORCEPROP 1 LAST PART_NUMBER CS00002JB13
J 0
(-400 -1975);
DISPLAY 0.404255 (-400 -1975);
DISPLAY INVISIBLE (-400 -1975);
FORCEADD Q_RES..1
(-300 -1975);
FORCEPROP 1 LAST LOCATION R3572
J 0
(-575 -1975);
DISPLAY 0.787234 (-575 -1975);
FORCEPROP 0 LAST $SEC 1
J 0
(-125 -1875);
DISPLAY 0.680851 (-125 -1875);
PAINT MONO (-125 -1875);
DISPLAY INVISIBLE (-125 -1875);
FORCEPROP 0 LAST CDS_SEC 1
J 0
(-125 -1875);
DISPLAY 0.680851 (-125 -1875);
DISPLAY INVISIBLE (-125 -1875);
FORCEPROP 1 LASTPIN (-400 -1975) $PN 1
J 0
(-388 -1963);
DISPLAY 0.787234 (-388 -1963);
PAINT MONO (-388 -1963);
FORCEPROP 1 LASTPIN (-200 -1975) $PN 2
J 0
(-238 -1963);
DISPLAY 0.787234 (-238 -1963);
PAINT MONO (-238 -1963);
FORCEPROP 1 LAST VALUE 0
J 2
(-125 -1975);
DISPLAY 0.638298 (-125 -1975);
FORCEPROP 1 LAST TOLERANCE 5%
J 0
(-100 -1975);
DISPLAY 0.638298 (-100 -1975);
FORCEPROP 1 LAST PACK_TYPE 0402LF
J 0
(-400 -1900);
DISPLAY 0.404255 (-400 -1900);
FORCEPROP 1 LAST MATERIAL CHIP
J 0
(0 -1975);
DISPLAY 0.638298 (0 -1975);
FORCEPROP 1 LAST WATTAGE 1/16W
J 2
(-125 -1900);
DISPLAY 0.510638 (-125 -1900);
FORCEPROP 2 LAST CDS_LIB pure_quanta
J 0
(-300 -1975);
DISPLAY INVISIBLE (-300 -1975);
FORCEPROP 1 LAST PATH I130
J 0
(-350 -1825);
DISPLAY 0.978723 (-350 -1825);
PAINT WHITE (-350 -1825);
DISPLAY INVISIBLE (-350 -1825);
FORCEPROP 1 LAST PART_NUMBER CS00002JB13
J 0
(-400 -1925);
DISPLAY 0.404255 (-400 -1925);
DISPLAY INVISIBLE (-400 -1925);
FORCEADD Q_RES..1
(-175 -4125);
FORCEPROP 1 LAST LOCATION R3576
J 0
(-450 -4125);
DISPLAY 0.787234 (-450 -4125);
FORCEPROP 0 LAST $SEC 1
J 0
(0 -4025);
DISPLAY 0.680851 (0 -4025);
PAINT MONO (0 -4025);
DISPLAY INVISIBLE (0 -4025);
FORCEPROP 0 LAST CDS_SEC 1
J 0
(0 -4025);
DISPLAY 0.680851 (0 -4025);
DISPLAY INVISIBLE (0 -4025);
FORCEPROP 1 LASTPIN (-275 -4125) $PN 1
J 0
(-263 -4113);
DISPLAY 0.787234 (-263 -4113);
PAINT MONO (-263 -4113);
FORCEPROP 1 LASTPIN (-75 -4125) $PN 2
J 0
(-113 -4113);
DISPLAY 0.787234 (-113 -4113);
PAINT MONO (-113 -4113);
FORCEPROP 1 LAST WATTAGE 1/16W
J 2
(0 -4050);
DISPLAY 0.510638 (0 -4050);
FORCEPROP 1 LAST MATERIAL CHIP
J 0
(125 -4125);
DISPLAY 0.638298 (125 -4125);
FORCEPROP 1 LAST TOLERANCE 5%
J 0
(25 -4125);
DISPLAY 0.638298 (25 -4125);
FORCEPROP 1 LAST VALUE 0
J 2
(0 -4125);
DISPLAY 0.638298 (0 -4125);
FORCEPROP 1 LAST PACK_TYPE 0402LF
J 0
(-275 -4050);
DISPLAY 0.404255 (-275 -4050);
FORCEPROP 2 LAST CDS_LIB pure_quanta
J 0
(-175 -4125);
DISPLAY INVISIBLE (-175 -4125);
FORCEPROP 1 LAST PATH I131
J 0
(-225 -3975);
DISPLAY 0.978723 (-225 -3975);
PAINT WHITE (-225 -3975);
DISPLAY INVISIBLE (-225 -3975);
FORCEPROP 1 LAST PART_NUMBER CS00002JB13
J 0
(-275 -4075);
DISPLAY 0.404255 (-275 -4075);
DISPLAY INVISIBLE (-275 -4075);
FORCEADD Q_RES..1
(-175 -4175);
FORCEPROP 1 LAST LOCATION R3577
J 0
(-450 -4175);
DISPLAY 0.787234 (-450 -4175);
FORCEPROP 0 LAST $SEC 1
J 0
(125 -4125);
DISPLAY 0.680851 (125 -4125);
PAINT MONO (125 -4125);
DISPLAY INVISIBLE (125 -4125);
FORCEPROP 0 LAST CDS_SEC 1
J 0
(125 -4125);
DISPLAY 0.680851 (125 -4125);
DISPLAY INVISIBLE (125 -4125);
FORCEPROP 1 LASTPIN (-275 -4175) $PN 1
J 0
(-263 -4163);
DISPLAY 0.787234 (-263 -4163);
PAINT MONO (-263 -4163);
FORCEPROP 1 LASTPIN (-75 -4175) $PN 2
J 0
(-113 -4163);
DISPLAY 0.787234 (-113 -4163);
PAINT MONO (-113 -4163);
FORCEPROP 1 LAST VALUE 0
J 2
(0 -4175);
DISPLAY 0.638298 (0 -4175);
FORCEPROP 1 LAST TOLERANCE 5%
J 0
(25 -4175);
DISPLAY 0.638298 (25 -4175);
FORCEPROP 1 LAST MATERIAL CHIP
J 0
(125 -4175);
DISPLAY 0.638298 (125 -4175);
FORCEPROP 1 LAST PACK_TYPE 0402LF
J 0
(-275 -4100);
DISPLAY 0.404255 (-275 -4100);
DISPLAY INVISIBLE (-275 -4100);
FORCEPROP 1 LAST WATTAGE 1/16W
J 2
(0 -4100);
DISPLAY 0.510638 (0 -4100);
DISPLAY INVISIBLE (0 -4100);
FORCEPROP 2 LAST CDS_LIB pure_quanta
J 0
(-175 -4175);
DISPLAY INVISIBLE (-175 -4175);
FORCEPROP 1 LAST PATH I132
J 0
(-225 -4025);
DISPLAY 0.978723 (-225 -4025);
PAINT WHITE (-225 -4025);
DISPLAY INVISIBLE (-225 -4025);
FORCEPROP 1 LAST PART_NUMBER CS00002JB13
J 0
(-275 -4125);
DISPLAY 0.404255 (-275 -4125);
DISPLAY INVISIBLE (-275 -4125);
FORCEADD UNIVERSAL_POWER..1
(-2750 -2225);
FORCEPROP 3 LASTPIN (-2750 -2275) SIG_NAME P3V3_M2_0\g
J 0
(-2740 -2265);
DISPLAY 0.659574 (-2740 -2265);
PAINT MONO (-2740 -2265);
DISPLAY INVISIBLE (-2740 -2265);
FORCEPROP 1 LAST HDL_POWER P3V3_M2_0
J 1
(-2750 -2175);
DISPLAY 0.872340 (-2750 -2175);
PAINT GREEN (-2750 -2175);
FORCEPROP 2 LAST CDS_LIB pure_quanta_power
J 0
(-2750 -2225);
DISPLAY INVISIBLE (-2750 -2225);
FORCEPROP 1 LAST PATH I24
J 0
(-2700 -2200);
DISPLAY 0.872340 (-2700 -2200);
PAINT AQUA (-2700 -2200);
DISPLAY INVISIBLE (-2700 -2200);
FORCEADD Q_CAP..1
(-2075 -1800);
FORCEPROP 1 LAST LOCATION C2018
J 0
(-2025 -1700);
DISPLAY 0.978723 (-2025 -1700);
FORCEPROP 0 LAST $SEC 1
J 0
(-2025 -1650);
DISPLAY 0.680851 (-2025 -1650);
PAINT MONO (-2025 -1650);
DISPLAY INVISIBLE (-2025 -1650);
FORCEPROP 0 LAST CDS_SEC 1
J 0
(-2025 -1650);
DISPLAY 1.021277 (-2025 -1650);
DISPLAY INVISIBLE (-2025 -1650);
FORCEPROP 1 LASTPIN (-2075 -1700) $PN 1
J 0
(-2065 -1720);
DISPLAY 0.787234 (-2065 -1720);
PAINT MONO (-2065 -1720);
FORCEPROP 1 LASTPIN (-2075 -1900) $PN 2
J 0
(-2065 -1920);
DISPLAY 0.787234 (-2065 -1920);
PAINT MONO (-2065 -1920);
FORCEPROP 1 LAST VALUE 0.1UF
J 0
(-2025 -1750);
DISPLAY 0.638298 (-2025 -1750);
FORCEPROP 1 LAST VOLTAGE 25V
J 0
(-2025 -1800);
DISPLAY 0.638298 (-2025 -1800);
FORCEPROP 1 LAST TOLERANCE 10%
J 0
(-2025 -1850);
DISPLAY 0.638298 (-2025 -1850);
FORCEPROP 1 LAST MATERIAL X7R
J 0
(-2025 -1900);
DISPLAY 0.638298 (-2025 -1900);
FORCEPROP 1 LAST PACK_TYPE 0402
J 0
(-2025 -1950);
DISPLAY 0.638298 (-2025 -1950);
FORCEPROP 2 LAST CDS_LIB pure_quanta
J 0
(-2075 -1800);
DISPLAY INVISIBLE (-2075 -1800);
FORCEPROP 1 LAST PATH I26
J 0
(-2025 -1650);
DISPLAY 0.978723 (-2025 -1650);
PAINT WHITE (-2025 -1650);
DISPLAY INVISIBLE (-2025 -1650);
FORCEPROP 1 LAST PART_NUMBER CH4104K1B00
J 0
(-2025 -1950);
DISPLAY 0.808511 (-2025 -1950);
DISPLAY INVISIBLE (-2025 -1950);
FORCEADD UNIVERSAL_GND..1
(-2075 -2075);
FORCEPROP 3 LASTPIN (-2075 -2025) SIG_NAME GND\g
J 0
(-2065 -2015);
DISPLAY 0.659574 (-2065 -2015);
PAINT MONO (-2065 -2015);
DISPLAY INVISIBLE (-2065 -2015);
FORCEPROP 2 LAST CDS_LIB pure_quanta_power
J 0
(-2075 -2075);
DISPLAY INVISIBLE (-2075 -2075);
FORCEPROP 1 LAST HDL_POWER GND
J 1
(-2050 -2150);
DISPLAY 0.872340 (-2050 -2150);
PAINT GREEN (-2050 -2150);
DISPLAY INVISIBLE (-2050 -2150);
FORCEPROP 1 LAST PATH I27
J 0
(-2000 -2075);
DISPLAY 0.872340 (-2000 -2075);
PAINT AQUA (-2000 -2075);
DISPLAY INVISIBLE (-2000 -2075);
FORCEADD OFFPAGE..3
R 2
(-1500 -2025);
FORCEPROP 2 LAST $XR0 252 
J 0
(-1780 -2025);
DISPLAY 0.638298 (-1780 -2025);
PAINT MONO (-1780 -2025);
FORCEPROP 2 LAST CDS_LIB standard
J 2
(-1500 -2025);
PAINT MONO (-1500 -2025);
DISPLAY INVISIBLE (-1500 -2025);
FORCEPROP 1 LAST OFFPAGE TRUE
J 2
(-1825 -2150);
DISPLAY 0.872340 (-1825 -2150);
DISPLAY INVISIBLE (-1825 -2150);
FORCEPROP 1 LAST COMMENT_BODY TRUE
J 2
(-1450 -2125);
DISPLAY 0.872340 (-1450 -2125);
PAINT GREEN (-1450 -2125);
DISPLAY INVISIBLE (-1450 -2125);
FORCEPROP 2 LAST PATH I29
J 0
(-1700 -1975);
DISPLAY 1.021277 (-1700 -1975);
DISPLAY INVISIBLE (-1700 -1975);
FORCEADD OFFPAGE..1
(-1500 -1975);
FORCEPROP 2 LAST $XR0 252 
J 0
(-1752 -1975);
DISPLAY 0.638298 (-1752 -1975);
PAINT MONO (-1752 -1975);
FORCEPROP 2 LAST CDS_LIB standard
J 0
(-1500 -1975);
DISPLAY INVISIBLE (-1500 -1975);
FORCEPROP 1 LAST OFFPAGE TRUE
J 0
(-1175 -2100);
DISPLAY 0.872340 (-1175 -2100);
DISPLAY INVISIBLE (-1175 -2100);
FORCEPROP 1 LAST COMMENT_BODY TRUE
J 0
(-1375 -2075);
DISPLAY 0.872340 (-1375 -2075);
PAINT GREEN (-1375 -2075);
DISPLAY INVISIBLE (-1375 -2075);
FORCEPROP 2 LAST PATH I30
J 0
(-1450 -1900);
DISPLAY 1.021277 (-1450 -1900);
DISPLAY INVISIBLE (-1450 -1900);
FORCEADD UNIVERSAL_GND..1
(-1475 -1875);
FORCEPROP 3 LASTPIN (-1475 -1825) SIG_NAME GND\g
J 0
(-1465 -1815);
DISPLAY 0.659574 (-1465 -1815);
PAINT MONO (-1465 -1815);
DISPLAY INVISIBLE (-1465 -1815);
FORCEPROP 2 LAST CDS_LIB pure_quanta_power
J 0
(-1475 -1875);
DISPLAY INVISIBLE (-1475 -1875);
FORCEPROP 1 LAST HDL_POWER GND
J 1
(-1450 -1950);
DISPLAY 0.872340 (-1450 -1950);
PAINT GREEN (-1450 -1950);
DISPLAY INVISIBLE (-1450 -1950);
FORCEPROP 1 LAST PATH I31
J 0
(-1400 -1875);
DISPLAY 0.872340 (-1400 -1875);
PAINT AQUA (-1400 -1875);
DISPLAY INVISIBLE (-1400 -1875);
FORCEADD UNIVERSAL_POWER..1
(-1825 -1475);
FORCEPROP 3 LASTPIN (-1825 -1525) SIG_NAME P3V3\g
J 0
(-1815 -1515);
DISPLAY 0.659574 (-1815 -1515);
PAINT MONO (-1815 -1515);
DISPLAY INVISIBLE (-1815 -1515);
FORCEPROP 1 LAST HDL_POWER P3V3
J 1
(-1825 -1425);
DISPLAY 0.872340 (-1825 -1425);
PAINT GREEN (-1825 -1425);
FORCEPROP 2 LAST CDS_LIB pure_quanta_power
J 0
(-1825 -1475);
DISPLAY INVISIBLE (-1825 -1475);
FORCEPROP 1 LAST PATH I32
J 0
(-1775 -1450);
DISPLAY 0.872340 (-1775 -1450);
PAINT AQUA (-1775 -1450);
DISPLAY INVISIBLE (-1775 -1450);
FORCEADD Q_RES..1
(-275 -2850);
FORCEPROP 1 LAST LOCATION R3575
J 0
(-525 -2850);
DISPLAY 0.638298 (-525 -2850);
FORCEPROP 0 LAST $SEC 1
J 0
(-425 -2750);
DISPLAY 0.680851 (-425 -2750);
PAINT MONO (-425 -2750);
DISPLAY INVISIBLE (-425 -2750);
FORCEPROP 0 LAST CDS_SEC 1
J 0
(-425 -2750);
DISPLAY 1.021277 (-425 -2750);
DISPLAY INVISIBLE (-425 -2750);
FORCEPROP 1 LASTPIN (-375 -2850) $PN 1
J 0
(-363 -2838);
DISPLAY 0.787234 (-363 -2838);
PAINT MONO (-363 -2838);
FORCEPROP 1 LASTPIN (-175 -2850) $PN 2
J 0
(-213 -2838);
DISPLAY 0.787234 (-213 -2838);
PAINT MONO (-213 -2838);
FORCEPROP 1 LAST PACK_TYPE 0402LF
J 0
(-150 -2900);
DISPLAY 0.638298 (-150 -2900);
FORCEPROP 1 LAST WATTAGE 1/16W
J 2
(-275 -2950);
DISPLAY 0.638298 (-275 -2950);
FORCEPROP 1 LAST MATERIAL CHIP
J 0
(-250 -2950);
DISPLAY 0.638298 (-250 -2950);
FORCEPROP 1 LAST TOLERANCE 1%
J 0
(-225 -2900);
DISPLAY 0.638298 (-225 -2900);
FORCEPROP 1 LAST VALUE 10
J 2
(-325 -2900);
DISPLAY 0.638298 (-325 -2900);
FORCEPROP 2 LAST CDS_LIB pure_quanta
J 0
(-275 -2850);
DISPLAY INVISIBLE (-275 -2850);
FORCEPROP 1 LAST PATH I33
J 0
(-325 -2700);
DISPLAY 0.978723 (-325 -2700);
PAINT WHITE (-325 -2700);
DISPLAY INVISIBLE (-325 -2700);
FORCEPROP 1 LAST PART_NUMBER CS01002FB07
J 0
(-425 -2800);
DISPLAY 0.638298 (-425 -2800);
DISPLAY INVISIBLE (-425 -2800);
FORCEADD Q_RES..1
(-275 -2575);
FORCEPROP 1 LAST LOCATION R3574
J 0
(-525 -2575);
DISPLAY 0.638298 (-525 -2575);
FORCEPROP 0 LAST $SEC 1
J 0
(-425 -2475);
DISPLAY 0.680851 (-425 -2475);
PAINT MONO (-425 -2475);
DISPLAY INVISIBLE (-425 -2475);
FORCEPROP 0 LAST CDS_SEC 1
J 0
(-425 -2475);
DISPLAY 1.021277 (-425 -2475);
DISPLAY INVISIBLE (-425 -2475);
FORCEPROP 1 LASTPIN (-375 -2575) $PN 1
J 0
(-363 -2563);
DISPLAY 0.787234 (-363 -2563);
PAINT MONO (-363 -2563);
FORCEPROP 1 LASTPIN (-175 -2575) $PN 2
J 0
(-213 -2563);
DISPLAY 0.787234 (-213 -2563);
PAINT MONO (-213 -2563);
FORCEPROP 1 LAST PACK_TYPE 0402LF
J 0
(-150 -2625);
DISPLAY 0.638298 (-150 -2625);
FORCEPROP 1 LAST WATTAGE 1/16W
J 2
(-275 -2675);
DISPLAY 0.638298 (-275 -2675);
FORCEPROP 1 LAST MATERIAL CHIP
J 0
(-250 -2675);
DISPLAY 0.638298 (-250 -2675);
FORCEPROP 1 LAST VALUE 10
J 2
(-325 -2625);
DISPLAY 0.638298 (-325 -2625);
FORCEPROP 1 LAST TOLERANCE 1%
J 0
(-225 -2625);
DISPLAY 0.638298 (-225 -2625);
FORCEPROP 2 LAST CDS_LIB pure_quanta
J 0
(-275 -2575);
DISPLAY INVISIBLE (-275 -2575);
FORCEPROP 1 LAST PATH I35
J 0
(-325 -2425);
DISPLAY 0.978723 (-325 -2425);
PAINT WHITE (-325 -2425);
DISPLAY INVISIBLE (-325 -2425);
FORCEPROP 1 LAST PART_NUMBER CS01002FB07
J 0
(-425 -2525);
DISPLAY 0.638298 (-425 -2525);
DISPLAY INVISIBLE (-425 -2525);
FORCEADD Q_RES..1
(-1050 -1750);
FORCEPROP 1 LAST LOCATION R3611
J 0
(-1175 -1750);
DISPLAY 0.638298 (-1175 -1750);
FORCEPROP 0 LAST $SEC 1
J 0
(-1175 -1700);
DISPLAY 0.680851 (-1175 -1700);
PAINT MONO (-1175 -1700);
DISPLAY INVISIBLE (-1175 -1700);
FORCEPROP 0 LAST CDS_SEC 1
J 0
(-1175 -1700);
DISPLAY 1.021277 (-1175 -1700);
DISPLAY INVISIBLE (-1175 -1700);
FORCEPROP 1 LASTPIN (-1150 -1750) $PN 1
J 0
(-1138 -1738);
DISPLAY 0.787234 (-1138 -1738);
PAINT MONO (-1138 -1738);
FORCEPROP 1 LASTPIN (-950 -1750) $PN 2
J 0
(-988 -1738);
DISPLAY 0.787234 (-988 -1738);
PAINT MONO (-988 -1738);
FORCEPROP 1 LAST PACK_TYPE 0402LF
J 0
(-575 -1750);
DISPLAY 0.510638 (-575 -1750);
FORCEPROP 1 LAST TOLERANCE 1%
J 0
(-725 -1750);
DISPLAY 0.510638 (-725 -1750);
FORCEPROP 1 LAST WATTAGE 1/16W
J 2
(-725 -1750);
DISPLAY 0.510638 (-725 -1750);
FORCEPROP 1 LAST MATERIAL CHIP
J 0
(-675 -1750);
DISPLAY 0.510638 (-675 -1750);
FORCEPROP 1 LAST VALUE 4.7K
J 2
(-850 -1750);
DISPLAY 0.510638 (-850 -1750);
FORCEPROP 2 LAST CDS_LIB pure_quanta
J 0
(-1050 -1750);
DISPLAY INVISIBLE (-1050 -1750);
FORCEPROP 1 LAST PATH I36
J 0
(-1100 -1600);
DISPLAY 0.978723 (-1100 -1600);
PAINT WHITE (-1100 -1600);
DISPLAY INVISIBLE (-1100 -1600);
FORCEPROP 1 LAST PART_NUMBER CS24702FB06
J 0
(-1475 -1750);
DISPLAY 0.510638 (-1475 -1750);
DISPLAY INVISIBLE (-1475 -1750);
FORCEADD UNIVERSAL_GND..1
(600 -1650);
FORCEPROP 3 LASTPIN (600 -1600) SIG_NAME GND\g
J 0
(610 -1590);
DISPLAY 0.659574 (610 -1590);
PAINT MONO (610 -1590);
DISPLAY INVISIBLE (610 -1590);
FORCEPROP 2 LAST CDS_LIB pure_quanta_power
J 0
(600 -1650);
DISPLAY INVISIBLE (600 -1650);
FORCEPROP 1 LAST HDL_POWER GND
J 1
(625 -1725);
DISPLAY 0.872340 (625 -1725);
PAINT GREEN (625 -1725);
DISPLAY INVISIBLE (625 -1725);
FORCEPROP 1 LAST PATH I39
J 0
(675 -1650);
DISPLAY 0.872340 (675 -1650);
PAINT AQUA (675 -1650);
DISPLAY INVISIBLE (675 -1650);
FORCEADD UNIVERSAL_GND..1
(1925 -2625);
FORCEPROP 3 LASTPIN (1925 -2575) SIG_NAME GND\g
J 0
(1935 -2565);
DISPLAY 0.659574 (1935 -2565);
PAINT MONO (1935 -2565);
DISPLAY INVISIBLE (1935 -2565);
FORCEPROP 2 LAST CDS_LIB pure_quanta_power
J 0
(1925 -2625);
DISPLAY INVISIBLE (1925 -2625);
FORCEPROP 1 LAST HDL_POWER GND
J 1
(1950 -2700);
DISPLAY 0.872340 (1950 -2700);
PAINT GREEN (1950 -2700);
DISPLAY INVISIBLE (1950 -2700);
FORCEPROP 1 LAST PATH I40
J 0
(2000 -2625);
DISPLAY 0.872340 (2000 -2625);
PAINT AQUA (2000 -2625);
DISPLAY INVISIBLE (2000 -2625);
FORCEADD Q_RES..1
(2800 -1725);
FORCEPROP 1 LAST LOCATION R3560
J 0
(2625 -1725);
DISPLAY 0.510638 (2625 -1725);
FORCEPROP 0 LAST $SEC 1
J 0
(3100 -1675);
DISPLAY 0.680851 (3100 -1675);
PAINT MONO (3100 -1675);
DISPLAY INVISIBLE (3100 -1675);
FORCEPROP 0 LAST CDS_SEC 1
J 0
(3100 -1675);
DISPLAY 1.021277 (3100 -1675);
DISPLAY INVISIBLE (3100 -1675);
FORCEPROP 1 LASTPIN (2700 -1725) $PN 1
J 0
(2712 -1713);
DISPLAY 0.787234 (2712 -1713);
PAINT MONO (2712 -1713);
FORCEPROP 1 LASTPIN (2900 -1725) $PN 2
J 0
(2862 -1713);
DISPLAY 0.787234 (2862 -1713);
PAINT MONO (2862 -1713);
FORCEPROP 1 LAST MATERIAL CHIP
J 0
(2975 -1725);
DISPLAY 0.574468 (2975 -1725);
FORCEPROP 1 LAST PACK_TYPE 0402LF
J 0
(3100 -1725);
DISPLAY 0.574468 (3100 -1725);
FORCEPROP 1 LAST VALUE 0
J 2
(2950 -1725);
DISPLAY 0.574468 (2950 -1725);
FORCEPROP 2 LAST CDS_LIB pure_quanta
J 0
(2800 -1725);
DISPLAY INVISIBLE (2800 -1725);
FORCEPROP 1 LAST TOLERANCE 5%
J 0
(2600 -1800);
DISPLAY 0.723404 (2600 -1800);
PAINT SKYBLUE (2600 -1800);
DISPLAY INVISIBLE (2600 -1800);
FORCEPROP 1 LAST WATTAGE 1/16W
J 2
(2875 -1800);
DISPLAY 0.723404 (2875 -1800);
PAINT SKYBLUE (2875 -1800);
DISPLAY INVISIBLE (2875 -1800);
FORCEPROP 1 LAST PATH I41
J 0
(2750 -1575);
DISPLAY 0.978723 (2750 -1575);
PAINT WHITE (2750 -1575);
DISPLAY INVISIBLE (2750 -1575);
FORCEPROP 1 LAST PART_NUMBER CS00002JB13
J 0
(2525 -1850);
DISPLAY 0.723404 (2525 -1850);
PAINT WHITE (2525 -1850);
DISPLAY INVISIBLE (2525 -1850);
FORCEADD Q_CAP..1
(600 -1375);
FORCEPROP 1 LAST LOCATION C2013
J 0
(650 -1275);
DISPLAY 0.978723 (650 -1275);
FORCEPROP 0 LAST $SEC 1
J 0
(650 -1225);
DISPLAY 0.680851 (650 -1225);
PAINT MONO (650 -1225);
DISPLAY INVISIBLE (650 -1225);
FORCEPROP 0 LAST CDS_SEC 1
J 0
(650 -1225);
DISPLAY 1.021277 (650 -1225);
DISPLAY INVISIBLE (650 -1225);
FORCEPROP 1 LASTPIN (600 -1275) $PN 1
J 0
(610 -1295);
DISPLAY 0.787234 (610 -1295);
PAINT MONO (610 -1295);
FORCEPROP 1 LASTPIN (600 -1475) $PN 2
J 0
(610 -1495);
DISPLAY 0.787234 (610 -1495);
PAINT MONO (610 -1495);
FORCEPROP 1 LAST MATERIAL X7R
J 0
(650 -1475);
DISPLAY 0.638298 (650 -1475);
FORCEPROP 1 LAST VALUE 0.1UF
J 0
(650 -1325);
DISPLAY 0.638298 (650 -1325);
FORCEPROP 1 LAST VOLTAGE 25V
J 0
(650 -1375);
DISPLAY 0.638298 (650 -1375);
FORCEPROP 1 LAST TOLERANCE 10%
J 0
(650 -1425);
DISPLAY 0.638298 (650 -1425);
FORCEPROP 1 LAST PACK_TYPE 0402
J 0
(650 -1525);
DISPLAY 0.638298 (650 -1525);
FORCEPROP 2 LAST CDS_LIB pure_quanta
J 0
(600 -1375);
DISPLAY INVISIBLE (600 -1375);
FORCEPROP 1 LAST PATH I42
J 0
(650 -1225);
DISPLAY 0.978723 (650 -1225);
PAINT WHITE (650 -1225);
DISPLAY INVISIBLE (650 -1225);
FORCEPROP 1 LAST PART_NUMBER CH4104K1B00
J 0
(650 -1525);
DISPLAY 0.808511 (650 -1525);
DISPLAY INVISIBLE (650 -1525);
FORCEADD UNIVERSAL_POWER..1
(850 -975);
FORCEPROP 3 LASTPIN (850 -1025) SIG_NAME P3V3_AUX\g
J 0
(860 -1015);
DISPLAY 0.659574 (860 -1015);
PAINT MONO (860 -1015);
DISPLAY INVISIBLE (860 -1015);
FORCEPROP 1 LAST HDL_POWER P3V3_AUX
J 1
(850 -925);
DISPLAY 0.872340 (850 -925);
PAINT GREEN (850 -925);
FORCEPROP 2 LAST CDS_LIB pure_quanta_power
J 0
(850 -975);
DISPLAY INVISIBLE (850 -975);
FORCEPROP 1 LAST PATH I43
J 0
(900 -950);
DISPLAY 0.872340 (900 -950);
PAINT AQUA (900 -950);
DISPLAY INVISIBLE (900 -950);
FORCEADD OFFPAGE..2
(3975 -1725);
FORCEPROP 2 LAST $XR0 82 
J 0
(4164 -1725);
DISPLAY 0.638298 (4164 -1725);
PAINT MONO (4164 -1725);
FORCEPROP 2 LAST CDS_LIB standard
J 0
(3975 -1725);
DISPLAY INVISIBLE (3975 -1725);
FORCEPROP 1 LAST OFFPAGE TRUE
J 0
(4300 -1850);
DISPLAY 0.872340 (4300 -1850);
DISPLAY INVISIBLE (4300 -1850);
FORCEPROP 1 LAST COMMENT_BODY TRUE
J 0
(3930 -1820);
DISPLAY 0.872340 (3930 -1820);
PAINT GREEN (3930 -1820);
DISPLAY INVISIBLE (3930 -1820);
FORCEPROP 2 LAST PATH I44
J 0
(4150 -1650);
DISPLAY 1.021277 (4150 -1650);
DISPLAY INVISIBLE (4150 -1650);
FORCEADD Q_RES..1
(-1050 -1675);
FORCEPROP 1 LAST LOCATION R3610
J 0
(-1175 -1675);
DISPLAY 0.638298 (-1175 -1675);
FORCEPROP 0 LAST $SEC 1
J 0
(-1175 -1625);
DISPLAY 0.680851 (-1175 -1625);
PAINT MONO (-1175 -1625);
DISPLAY INVISIBLE (-1175 -1625);
FORCEPROP 0 LAST CDS_SEC 1
J 0
(-1175 -1625);
DISPLAY 1.021277 (-1175 -1625);
DISPLAY INVISIBLE (-1175 -1625);
FORCEPROP 1 LASTPIN (-1150 -1675) $PN 1
J 0
(-1138 -1663);
DISPLAY 0.787234 (-1138 -1663);
PAINT MONO (-1138 -1663);
FORCEPROP 1 LASTPIN (-950 -1675) $PN 2
J 0
(-988 -1663);
DISPLAY 0.787234 (-988 -1663);
PAINT MONO (-988 -1663);
FORCEPROP 1 LAST PACK_TYPE 0402LF
J 0
(-575 -1675);
DISPLAY 0.510638 (-575 -1675);
FORCEPROP 1 LAST VALUE 4.7K
J 2
(-850 -1675);
DISPLAY 0.510638 (-850 -1675);
FORCEPROP 1 LAST TOLERANCE 1%
J 0
(-725 -1675);
DISPLAY 0.510638 (-725 -1675);
FORCEPROP 1 LAST WATTAGE 1/16W
J 2
(-725 -1675);
DISPLAY 0.510638 (-725 -1675);
FORCEPROP 1 LAST MATERIAL EMPTY
J 0
(-675 -1675);
DISPLAY 0.510638 (-675 -1675);
PAINT RED (-675 -1675);
FORCEPROP 2 LAST CDS_LIB pure_quanta
J 0
(-1050 -1675);
DISPLAY INVISIBLE (-1050 -1675);
FORCEPROP 1 LAST PATH I45
J 0
(-1100 -1525);
DISPLAY 0.978723 (-1100 -1525);
PAINT WHITE (-1100 -1525);
DISPLAY INVISIBLE (-1100 -1525);
FORCEPROP 1 LAST PART_NUMBER CS24702FB06
J 0
(-1475 -1675);
DISPLAY 0.510638 (-1475 -1675);
DISPLAY INVISIBLE (-1475 -1675);
FORCEADD ISL28022FRZT..1
(1350 -1975);
FORCEPROP 1 LAST LOCATION U264
J 0
(1055 -1394);
DISPLAY 0.723404 (1055 -1394);
PAINT GREEN (1055 -1394);
FORCEPROP 2 LAST SEC 1
J 0
(1075 -1250);
DISPLAY 0.680851 (1075 -1250);
PAINT MONO (1075 -1250);
DISPLAY INVISIBLE (1075 -1250);
FORCEPROP 2 LASTPIN (900 -1875) $PN 2
J 2
(890 -1865);
DISPLAY 0.680851 (890 -1865);
PAINT MONO (890 -1865);
FORCEPROP 2 LASTPIN (900 -1825) $PN 1
J 2
(890 -1815);
DISPLAY 0.680851 (890 -1815);
PAINT MONO (890 -1815);
FORCEPROP 2 LASTPIN (1800 -1725) $PN 3
J 0
(1810 -1715);
DISPLAY 0.680851 (1810 -1715);
PAINT MONO (1810 -1715);
FORCEPROP 2 LASTPIN (1800 -2175) $PN 10
J 0
(1810 -2165);
DISPLAY 0.680851 (1810 -2165);
PAINT MONO (1810 -2165);
FORCEPROP 2 LASTPIN (1800 -1825) $PN 6
J 0
(1810 -1815);
DISPLAY 0.680851 (1810 -1815);
PAINT MONO (1810 -1815);
FORCEPROP 2 LASTPIN (1800 -1875) $PN 7
J 0
(1810 -1865);
DISPLAY 0.680851 (1810 -1865);
PAINT MONO (1810 -1865);
FORCEPROP 2 LASTPIN (1800 -1925) $PN 8
J 0
(1810 -1915);
DISPLAY 0.680851 (1810 -1915);
PAINT MONO (1810 -1915);
FORCEPROP 2 LASTPIN (1800 -1975) $PN 14
J 0
(1810 -1965);
DISPLAY 0.680851 (1810 -1965);
PAINT MONO (1810 -1965);
FORCEPROP 2 LASTPIN (1800 -2025) $PN 15
J 0
(1810 -2015);
DISPLAY 0.680851 (1810 -2015);
PAINT MONO (1810 -2015);
FORCEPROP 2 LASTPIN (1800 -2075) $PN 16
J 0
(1810 -2065);
DISPLAY 0.680851 (1810 -2065);
PAINT MONO (1810 -2065);
FORCEPROP 2 LASTPIN (900 -1975) $PN 5
J 2
(890 -1965);
DISPLAY 0.680851 (890 -1965);
PAINT MONO (890 -1965);
FORCEPROP 2 LASTPIN (900 -2025) $PN 4
J 2
(890 -2015);
DISPLAY 0.680851 (890 -2015);
PAINT MONO (890 -2015);
FORCEPROP 2 LASTPIN (1800 -2225) $PN TH
J 0
(1810 -2215);
DISPLAY 0.680851 (1810 -2215);
PAINT MONO (1810 -2215);
FORCEPROP 2 LASTPIN (900 -2125) $PN 11
J 2
(890 -2115);
DISPLAY 0.680851 (890 -2115);
PAINT MONO (890 -2115);
FORCEPROP 2 LASTPIN (900 -1725) $PN 9
J 2
(890 -1715);
DISPLAY 0.680851 (890 -1715);
PAINT MONO (890 -1715);
FORCEPROP 2 LASTPIN (900 -2225) $PN 12
J 2
(890 -2215);
DISPLAY 0.680851 (890 -2215);
PAINT MONO (890 -2215);
FORCEPROP 2 LASTPIN (900 -2175) $PN 13
J 2
(890 -2165);
DISPLAY 0.680851 (890 -2165);
PAINT MONO (890 -2165);
FORCEPROP 1 LAST MATERIAL IC
J 0
(1055 -1668);
DISPLAY 0.723404 (1055 -1668);
PAINT GREEN (1055 -1668);
FORCEPROP 2 LAST PART_TYPE SMLF
J 0
(1075 -1300);
DISPLAY 1.021277 (1075 -1300);
FORCEPROP 2 LAST VALUE ISL28022FRZ-T
J 0
(1075 -1350);
DISPLAY 1.021277 (1075 -1350);
FORCEPROP 2 LAST CDS_LIB pure_quanta
J 0
(1350 -1975);
DISPLAY INVISIBLE (1350 -1975);
FORCEPROP 1 LAST NEEDS_NO_SIZE TRUE
J 0
(1350 -1975);
DISPLAY 0.723404 (1350 -1975);
PAINT GREEN (1350 -1975);
DISPLAY INVISIBLE (1350 -1975);
FORCEPROP 1 LAST CDS_LMAN_SYM_OUTLINE -300,300,300,-300
J 0
(1350 -1975);
DISPLAY 0.468085 (1350 -1975);
PAINT GREEN (1350 -1975);
DISPLAY INVISIBLE (1350 -1975);
FORCEPROP 2 LAST SEC_TYPE 
J 0
(1075 -1250);
DISPLAY 1.021277 (1075 -1250);
DISPLAY INVISIBLE (1075 -1250);
FORCEPROP 1 LAST PATH I46
J 0
(1350 -1975);
DISPLAY 0.723404 (1350 -1975);
PAINT GREEN (1350 -1975);
DISPLAY INVISIBLE (1350 -1975);
FORCEPROP 1 LAST PART_NUMBER AL028022003
J 0
(1055 -1541);
DISPLAY 0.723404 (1055 -1541);
PAINT GREEN (1055 -1541);
DISPLAY INVISIBLE (1055 -1541);
FORCEADD Q_CAP..1
(-1950 -3950);
FORCEPROP 1 LAST LOCATION C2019
J 0
(-1900 -3850);
DISPLAY 0.978723 (-1900 -3850);
FORCEPROP 0 LAST $SEC 1
J 0
(-1900 -3800);
DISPLAY 0.680851 (-1900 -3800);
PAINT MONO (-1900 -3800);
DISPLAY INVISIBLE (-1900 -3800);
FORCEPROP 0 LAST CDS_SEC 1
J 0
(-1900 -3800);
DISPLAY 1.021277 (-1900 -3800);
DISPLAY INVISIBLE (-1900 -3800);
FORCEPROP 1 LASTPIN (-1950 -3850) $PN 1
J 0
(-1940 -3870);
DISPLAY 0.787234 (-1940 -3870);
PAINT MONO (-1940 -3870);
FORCEPROP 1 LASTPIN (-1950 -4050) $PN 2
J 0
(-1940 -4070);
DISPLAY 0.787234 (-1940 -4070);
PAINT MONO (-1940 -4070);
FORCEPROP 1 LAST PACK_TYPE 0402
J 0
(-1900 -4100);
DISPLAY 0.638298 (-1900 -4100);
FORCEPROP 1 LAST VALUE 0.1UF
J 0
(-1900 -3900);
DISPLAY 0.638298 (-1900 -3900);
FORCEPROP 1 LAST MATERIAL X7R
J 0
(-1900 -4050);
DISPLAY 0.638298 (-1900 -4050);
FORCEPROP 1 LAST VOLTAGE 25V
J 0
(-1900 -3950);
DISPLAY 0.638298 (-1900 -3950);
FORCEPROP 1 LAST TOLERANCE 10%
J 0
(-1900 -4000);
DISPLAY 0.638298 (-1900 -4000);
FORCEPROP 2 LAST CDS_LIB pure_quanta
J 0
(-1950 -3950);
DISPLAY INVISIBLE (-1950 -3950);
FORCEPROP 1 LAST PATH I49
J 0
(-1900 -3800);
DISPLAY 0.978723 (-1900 -3800);
PAINT WHITE (-1900 -3800);
DISPLAY INVISIBLE (-1900 -3800);
FORCEPROP 1 LAST PART_NUMBER CH4104K1B00
J 0
(-1900 -4100);
DISPLAY 0.808511 (-1900 -4100);
DISPLAY INVISIBLE (-1900 -4100);
FORCEADD UNIVERSAL_GND..1
(-1950 -4225);
FORCEPROP 3 LASTPIN (-1950 -4175) SIG_NAME GND\g
J 0
(-1940 -4165);
DISPLAY 0.659574 (-1940 -4165);
PAINT MONO (-1940 -4165);
DISPLAY INVISIBLE (-1940 -4165);
FORCEPROP 2 LAST CDS_LIB pure_quanta_power
J 0
(-1950 -4225);
DISPLAY INVISIBLE (-1950 -4225);
FORCEPROP 1 LAST HDL_POWER GND
J 1
(-1925 -4300);
DISPLAY 0.872340 (-1925 -4300);
PAINT GREEN (-1925 -4300);
DISPLAY INVISIBLE (-1925 -4300);
FORCEPROP 1 LAST PATH I50
J 0
(-1875 -4225);
DISPLAY 0.872340 (-1875 -4225);
PAINT AQUA (-1875 -4225);
DISPLAY INVISIBLE (-1875 -4225);
FORCEADD OFFPAGE..3
R 2
(-1375 -4175);
FORCEPROP 2 LAST $XR0 252 
J 0
(-1655 -4175);
DISPLAY 0.638298 (-1655 -4175);
PAINT MONO (-1655 -4175);
FORCEPROP 2 LAST CDS_LIB standard
J 2
(-1375 -4175);
PAINT MONO (-1375 -4175);
DISPLAY INVISIBLE (-1375 -4175);
FORCEPROP 1 LAST OFFPAGE TRUE
J 2
(-1700 -4300);
DISPLAY 0.872340 (-1700 -4300);
DISPLAY INVISIBLE (-1700 -4300);
FORCEPROP 1 LAST COMMENT_BODY TRUE
J 2
(-1325 -4275);
DISPLAY 0.872340 (-1325 -4275);
PAINT GREEN (-1325 -4275);
DISPLAY INVISIBLE (-1325 -4275);
FORCEPROP 2 LAST PATH I52
J 0
(-1575 -4125);
DISPLAY 1.021277 (-1575 -4125);
DISPLAY INVISIBLE (-1575 -4125);
FORCEADD OFFPAGE..1
(-1375 -4125);
FORCEPROP 2 LAST $XR0 252 
J 0
(-1627 -4125);
DISPLAY 0.638298 (-1627 -4125);
PAINT MONO (-1627 -4125);
FORCEPROP 2 LAST CDS_LIB standard
J 0
(-1375 -4125);
DISPLAY INVISIBLE (-1375 -4125);
FORCEPROP 1 LAST OFFPAGE TRUE
J 0
(-1050 -4250);
DISPLAY 0.872340 (-1050 -4250);
DISPLAY INVISIBLE (-1050 -4250);
FORCEPROP 1 LAST COMMENT_BODY TRUE
J 0
(-1250 -4225);
DISPLAY 0.872340 (-1250 -4225);
PAINT GREEN (-1250 -4225);
DISPLAY INVISIBLE (-1250 -4225);
FORCEPROP 2 LAST PATH I53
J 0
(-1325 -4050);
DISPLAY 1.021277 (-1325 -4050);
DISPLAY INVISIBLE (-1325 -4050);
FORCEADD UNIVERSAL_GND..1
(-1400 -4050);
FORCEPROP 3 LASTPIN (-1400 -4000) SIG_NAME GND\g
J 0
(-1390 -3990);
DISPLAY 0.659574 (-1390 -3990);
PAINT MONO (-1390 -3990);
DISPLAY INVISIBLE (-1390 -3990);
FORCEPROP 2 LAST CDS_LIB pure_quanta_power
J 0
(-1400 -4050);
DISPLAY INVISIBLE (-1400 -4050);
FORCEPROP 1 LAST HDL_POWER GND
J 1
(-1375 -4125);
DISPLAY 0.872340 (-1375 -4125);
PAINT GREEN (-1375 -4125);
DISPLAY INVISIBLE (-1375 -4125);
FORCEPROP 1 LAST PATH I54
J 0
(-1325 -4050);
DISPLAY 0.872340 (-1325 -4050);
PAINT AQUA (-1325 -4050);
DISPLAY INVISIBLE (-1325 -4050);
FORCEADD Q_RES..1
(-150 -5000);
FORCEPROP 1 LAST LOCATION R3579
J 0
(-400 -5000);
DISPLAY 0.638298 (-400 -5000);
FORCEPROP 0 LAST $SEC 1
J 0
(-300 -4900);
DISPLAY 0.680851 (-300 -4900);
PAINT MONO (-300 -4900);
DISPLAY INVISIBLE (-300 -4900);
FORCEPROP 0 LAST CDS_SEC 1
J 0
(-300 -4900);
DISPLAY 1.021277 (-300 -4900);
DISPLAY INVISIBLE (-300 -4900);
FORCEPROP 1 LASTPIN (-250 -5000) $PN 1
J 0
(-238 -4988);
DISPLAY 0.787234 (-238 -4988);
PAINT MONO (-238 -4988);
FORCEPROP 1 LASTPIN (-50 -5000) $PN 2
J 0
(-88 -4988);
DISPLAY 0.787234 (-88 -4988);
PAINT MONO (-88 -4988);
FORCEPROP 1 LAST WATTAGE 1/16W
J 2
(-150 -5100);
DISPLAY 0.638298 (-150 -5100);
FORCEPROP 1 LAST TOLERANCE 1%
J 0
(-100 -5050);
DISPLAY 0.638298 (-100 -5050);
FORCEPROP 1 LAST VALUE 10
J 2
(-200 -5050);
DISPLAY 0.638298 (-200 -5050);
FORCEPROP 1 LAST PACK_TYPE 0402LF
J 0
(-25 -5050);
DISPLAY 0.638298 (-25 -5050);
FORCEPROP 1 LAST MATERIAL CHIP
J 0
(-125 -5100);
DISPLAY 0.638298 (-125 -5100);
FORCEPROP 2 LAST CDS_LIB pure_quanta
J 0
(-150 -5000);
DISPLAY INVISIBLE (-150 -5000);
FORCEPROP 1 LAST PATH I56
J 0
(-200 -4850);
DISPLAY 0.978723 (-200 -4850);
PAINT WHITE (-200 -4850);
DISPLAY INVISIBLE (-200 -4850);
FORCEPROP 1 LAST PART_NUMBER CS01002FB07
J 0
(-300 -4950);
DISPLAY 0.638298 (-300 -4950);
DISPLAY INVISIBLE (-300 -4950);
FORCEADD Q_RES..1
(-150 -4725);
FORCEPROP 1 LAST LOCATION R3578
J 0
(-400 -4725);
DISPLAY 0.638298 (-400 -4725);
FORCEPROP 0 LAST $SEC 1
J 0
(-300 -4625);
DISPLAY 0.680851 (-300 -4625);
PAINT MONO (-300 -4625);
DISPLAY INVISIBLE (-300 -4625);
FORCEPROP 0 LAST CDS_SEC 1
J 0
(-300 -4625);
DISPLAY 1.021277 (-300 -4625);
DISPLAY INVISIBLE (-300 -4625);
FORCEPROP 1 LASTPIN (-250 -4725) $PN 1
J 0
(-238 -4713);
DISPLAY 0.787234 (-238 -4713);
PAINT MONO (-238 -4713);
FORCEPROP 1 LASTPIN (-50 -4725) $PN 2
J 0
(-88 -4713);
DISPLAY 0.787234 (-88 -4713);
PAINT MONO (-88 -4713);
FORCEPROP 1 LAST MATERIAL CHIP
J 0
(-125 -4825);
DISPLAY 0.638298 (-125 -4825);
FORCEPROP 1 LAST VALUE 10
J 2
(-200 -4775);
DISPLAY 0.638298 (-200 -4775);
FORCEPROP 1 LAST TOLERANCE 1%
J 0
(-100 -4775);
DISPLAY 0.638298 (-100 -4775);
FORCEPROP 1 LAST PACK_TYPE 0402LF
J 0
(-25 -4775);
DISPLAY 0.638298 (-25 -4775);
FORCEPROP 1 LAST WATTAGE 1/16W
J 2
(-150 -4825);
DISPLAY 0.638298 (-150 -4825);
FORCEPROP 2 LAST CDS_LIB pure_quanta
J 0
(-150 -4725);
DISPLAY INVISIBLE (-150 -4725);
FORCEPROP 1 LAST PATH I58
J 0
(-200 -4575);
DISPLAY 0.978723 (-200 -4575);
PAINT WHITE (-200 -4575);
DISPLAY INVISIBLE (-200 -4575);
FORCEPROP 1 LAST PART_NUMBER CS01002FB07
J 0
(-300 -4675);
DISPLAY 0.638298 (-300 -4675);
DISPLAY INVISIBLE (-300 -4675);
FORCEADD Q_RES..1
(-975 -3925);
FORCEPROP 1 LAST LOCATION R3613
J 0
(-1100 -3925);
DISPLAY 0.638298 (-1100 -3925);
FORCEPROP 0 LAST $SEC 1
J 0
(-1100 -3875);
DISPLAY 0.680851 (-1100 -3875);
PAINT MONO (-1100 -3875);
DISPLAY INVISIBLE (-1100 -3875);
FORCEPROP 0 LAST CDS_SEC 1
J 0
(-1100 -3875);
DISPLAY 1.021277 (-1100 -3875);
DISPLAY INVISIBLE (-1100 -3875);
FORCEPROP 1 LASTPIN (-1075 -3925) $PN 1
J 0
(-1063 -3913);
DISPLAY 0.787234 (-1063 -3913);
PAINT MONO (-1063 -3913);
FORCEPROP 1 LASTPIN (-875 -3925) $PN 2
J 0
(-913 -3913);
DISPLAY 0.787234 (-913 -3913);
PAINT MONO (-913 -3913);
FORCEPROP 1 LAST WATTAGE 1/16W
J 2
(-650 -3925);
DISPLAY 0.510638 (-650 -3925);
FORCEPROP 1 LAST MATERIAL EMPTY
J 0
(-600 -3925);
DISPLAY 0.510638 (-600 -3925);
PAINT RED (-600 -3925);
FORCEPROP 1 LAST PACK_TYPE 0402LF
J 0
(-500 -3925);
DISPLAY 0.510638 (-500 -3925);
FORCEPROP 1 LAST TOLERANCE 1%
J 0
(-650 -3925);
DISPLAY 0.510638 (-650 -3925);
FORCEPROP 1 LAST VALUE 4.7K
J 2
(-775 -3925);
DISPLAY 0.510638 (-775 -3925);
FORCEPROP 2 LAST CDS_LIB pure_quanta
J 0
(-975 -3925);
DISPLAY INVISIBLE (-975 -3925);
FORCEPROP 1 LAST PATH I59
J 0
(-1025 -3775);
DISPLAY 0.978723 (-1025 -3775);
PAINT WHITE (-1025 -3775);
DISPLAY INVISIBLE (-1025 -3775);
FORCEPROP 1 LAST PART_NUMBER CS24702FB06
J 0
(-1400 -3925);
DISPLAY 0.510638 (-1400 -3925);
DISPLAY INVISIBLE (-1400 -3925);
FORCEADD UNIVERSAL_GND..1
(725 -3800);
FORCEPROP 3 LASTPIN (725 -3750) SIG_NAME GND\g
J 0
(735 -3740);
DISPLAY 0.659574 (735 -3740);
PAINT MONO (735 -3740);
DISPLAY INVISIBLE (735 -3740);
FORCEPROP 2 LAST CDS_LIB pure_quanta_power
J 0
(725 -3800);
DISPLAY INVISIBLE (725 -3800);
FORCEPROP 1 LAST HDL_POWER GND
J 1
(750 -3875);
DISPLAY 0.872340 (750 -3875);
PAINT GREEN (750 -3875);
DISPLAY INVISIBLE (750 -3875);
FORCEPROP 1 LAST PATH I62
J 0
(800 -3800);
DISPLAY 0.872340 (800 -3800);
PAINT AQUA (800 -3800);
DISPLAY INVISIBLE (800 -3800);
FORCEADD UNIVERSAL_GND..1
(2050 -4775);
FORCEPROP 3 LASTPIN (2050 -4725) SIG_NAME GND\g
J 0
(2060 -4715);
DISPLAY 0.659574 (2060 -4715);
PAINT MONO (2060 -4715);
DISPLAY INVISIBLE (2060 -4715);
FORCEPROP 2 LAST CDS_LIB pure_quanta_power
J 0
(2050 -4775);
DISPLAY INVISIBLE (2050 -4775);
FORCEPROP 1 LAST HDL_POWER GND
J 1
(2075 -4850);
DISPLAY 0.872340 (2075 -4850);
PAINT GREEN (2075 -4850);
DISPLAY INVISIBLE (2075 -4850);
FORCEPROP 1 LAST PATH I63
J 0
(2125 -4775);
DISPLAY 0.872340 (2125 -4775);
PAINT AQUA (2125 -4775);
DISPLAY INVISIBLE (2125 -4775);
FORCEADD Q_RES..1
(2925 -3875);
FORCEPROP 1 LAST LOCATION R3561
J 0
(2750 -3875);
DISPLAY 0.510638 (2750 -3875);
FORCEPROP 0 LAST $SEC 1
J 0
(3225 -3825);
DISPLAY 0.680851 (3225 -3825);
PAINT MONO (3225 -3825);
DISPLAY INVISIBLE (3225 -3825);
FORCEPROP 0 LAST CDS_SEC 1
J 0
(3225 -3825);
DISPLAY 1.021277 (3225 -3825);
DISPLAY INVISIBLE (3225 -3825);
FORCEPROP 1 LASTPIN (2825 -3875) $PN 1
J 0
(2837 -3863);
DISPLAY 0.787234 (2837 -3863);
PAINT MONO (2837 -3863);
FORCEPROP 1 LASTPIN (3025 -3875) $PN 2
J 0
(2987 -3863);
DISPLAY 0.787234 (2987 -3863);
PAINT MONO (2987 -3863);
FORCEPROP 1 LAST VALUE 0
J 2
(3075 -3875);
DISPLAY 0.574468 (3075 -3875);
FORCEPROP 1 LAST MATERIAL CHIP
J 0
(3100 -3875);
DISPLAY 0.574468 (3100 -3875);
FORCEPROP 1 LAST PACK_TYPE 0402LF
J 0
(3225 -3875);
DISPLAY 0.574468 (3225 -3875);
FORCEPROP 1 LAST WATTAGE 1/16W
J 2
(3000 -3950);
DISPLAY 0.723404 (3000 -3950);
PAINT SKYBLUE (3000 -3950);
DISPLAY INVISIBLE (3000 -3950);
FORCEPROP 1 LAST TOLERANCE 5%
J 0
(2725 -3950);
DISPLAY 0.723404 (2725 -3950);
PAINT SKYBLUE (2725 -3950);
DISPLAY INVISIBLE (2725 -3950);
FORCEPROP 2 LAST CDS_LIB pure_quanta
J 0
(2925 -3875);
DISPLAY INVISIBLE (2925 -3875);
FORCEPROP 1 LAST PATH I64
J 0
(2875 -3725);
DISPLAY 0.978723 (2875 -3725);
PAINT WHITE (2875 -3725);
DISPLAY INVISIBLE (2875 -3725);
FORCEPROP 1 LAST PART_NUMBER CS00002JB13
J 0
(2650 -4000);
DISPLAY 0.723404 (2650 -4000);
PAINT WHITE (2650 -4000);
DISPLAY INVISIBLE (2650 -4000);
FORCEADD Q_CAP..1
(725 -3525);
FORCEPROP 1 LAST LOCATION C2014
J 0
(775 -3425);
DISPLAY 0.978723 (775 -3425);
FORCEPROP 0 LAST $SEC 1
J 0
(775 -3375);
DISPLAY 0.680851 (775 -3375);
PAINT MONO (775 -3375);
DISPLAY INVISIBLE (775 -3375);
FORCEPROP 0 LAST CDS_SEC 1
J 0
(775 -3375);
DISPLAY 1.021277 (775 -3375);
DISPLAY INVISIBLE (775 -3375);
FORCEPROP 1 LASTPIN (725 -3425) $PN 1
J 0
(735 -3445);
DISPLAY 0.787234 (735 -3445);
PAINT MONO (735 -3445);
FORCEPROP 1 LASTPIN (725 -3625) $PN 2
J 0
(735 -3645);
DISPLAY 0.787234 (735 -3645);
PAINT MONO (735 -3645);
FORCEPROP 1 LAST TOLERANCE 10%
J 0
(775 -3575);
DISPLAY 0.638298 (775 -3575);
FORCEPROP 1 LAST VOLTAGE 25V
J 0
(775 -3525);
DISPLAY 0.638298 (775 -3525);
FORCEPROP 1 LAST VALUE 0.1UF
J 0
(775 -3475);
DISPLAY 0.638298 (775 -3475);
FORCEPROP 1 LAST MATERIAL X7R
J 0
(775 -3625);
DISPLAY 0.638298 (775 -3625);
FORCEPROP 1 LAST PACK_TYPE 0402
J 0
(775 -3675);
DISPLAY 0.638298 (775 -3675);
FORCEPROP 2 LAST CDS_LIB pure_quanta
J 0
(725 -3525);
DISPLAY INVISIBLE (725 -3525);
FORCEPROP 1 LAST PATH I65
J 0
(775 -3375);
DISPLAY 0.978723 (775 -3375);
PAINT WHITE (775 -3375);
DISPLAY INVISIBLE (775 -3375);
FORCEPROP 1 LAST PART_NUMBER CH4104K1B00
J 0
(775 -3675);
DISPLAY 0.808511 (775 -3675);
DISPLAY INVISIBLE (775 -3675);
FORCEADD UNIVERSAL_POWER..1
(975 -3125);
FORCEPROP 3 LASTPIN (975 -3175) SIG_NAME P3V3_AUX\g
J 0
(985 -3165);
DISPLAY 0.659574 (985 -3165);
PAINT MONO (985 -3165);
DISPLAY INVISIBLE (985 -3165);
FORCEPROP 1 LAST HDL_POWER P3V3_AUX
J 1
(975 -3075);
DISPLAY 0.872340 (975 -3075);
PAINT GREEN (975 -3075);
FORCEPROP 2 LAST CDS_LIB pure_quanta_power
J 0
(975 -3125);
DISPLAY INVISIBLE (975 -3125);
FORCEPROP 1 LAST PATH I66
J 0
(1025 -3100);
DISPLAY 0.872340 (1025 -3100);
PAINT AQUA (1025 -3100);
DISPLAY INVISIBLE (1025 -3100);
FORCEADD OFFPAGE..2
(4100 -3875);
FORCEPROP 2 LAST $XR0 82 
J 0
(4289 -3875);
DISPLAY 0.638298 (4289 -3875);
PAINT MONO (4289 -3875);
FORCEPROP 2 LAST CDS_LIB standard
J 0
(4100 -3875);
DISPLAY INVISIBLE (4100 -3875);
FORCEPROP 1 LAST OFFPAGE TRUE
J 0
(4425 -4000);
DISPLAY 0.872340 (4425 -4000);
DISPLAY INVISIBLE (4425 -4000);
FORCEPROP 1 LAST COMMENT_BODY TRUE
J 0
(4055 -3970);
DISPLAY 0.872340 (4055 -3970);
PAINT GREEN (4055 -3970);
DISPLAY INVISIBLE (4055 -3970);
FORCEPROP 2 LAST PATH I67
J 0
(4275 -3800);
DISPLAY 1.021277 (4275 -3800);
DISPLAY INVISIBLE (4275 -3800);
FORCEADD Q_RES..1
(-975 -3850);
FORCEPROP 1 LAST LOCATION R3612
J 0
(-1100 -3850);
DISPLAY 0.638298 (-1100 -3850);
FORCEPROP 0 LAST $SEC 1
J 0
(-1100 -3800);
DISPLAY 0.680851 (-1100 -3800);
PAINT MONO (-1100 -3800);
DISPLAY INVISIBLE (-1100 -3800);
FORCEPROP 0 LAST CDS_SEC 1
J 0
(-1100 -3800);
DISPLAY 1.021277 (-1100 -3800);
DISPLAY INVISIBLE (-1100 -3800);
FORCEPROP 1 LASTPIN (-1075 -3850) $PN 1
J 0
(-1063 -3838);
DISPLAY 0.787234 (-1063 -3838);
PAINT MONO (-1063 -3838);
FORCEPROP 1 LASTPIN (-875 -3850) $PN 2
J 0
(-913 -3838);
DISPLAY 0.787234 (-913 -3838);
PAINT MONO (-913 -3838);
FORCEPROP 1 LAST WATTAGE 1/16W
J 2
(-650 -3850);
DISPLAY 0.510638 (-650 -3850);
FORCEPROP 1 LAST MATERIAL EMPTY
J 0
(-600 -3850);
DISPLAY 0.510638 (-600 -3850);
PAINT RED (-600 -3850);
FORCEPROP 1 LAST TOLERANCE 1%
J 0
(-650 -3850);
DISPLAY 0.510638 (-650 -3850);
FORCEPROP 1 LAST VALUE 4.7K
J 2
(-775 -3850);
DISPLAY 0.510638 (-775 -3850);
FORCEPROP 1 LAST PACK_TYPE 0402LF
J 0
(-500 -3850);
DISPLAY 0.510638 (-500 -3850);
FORCEPROP 2 LAST CDS_LIB pure_quanta
J 0
(-975 -3850);
DISPLAY INVISIBLE (-975 -3850);
FORCEPROP 1 LAST PATH I68
J 0
(-1025 -3700);
DISPLAY 0.978723 (-1025 -3700);
PAINT WHITE (-1025 -3700);
DISPLAY INVISIBLE (-1025 -3700);
FORCEPROP 1 LAST PART_NUMBER CS24702FB06
J 0
(-1400 -3850);
DISPLAY 0.510638 (-1400 -3850);
DISPLAY INVISIBLE (-1400 -3850);
FORCEADD ISL28022FRZT..1
(1475 -4125);
FORCEPROP 1 LAST LOCATION U265
J 0
(1180 -3544);
DISPLAY 0.723404 (1180 -3544);
PAINT GREEN (1180 -3544);
FORCEPROP 2 LAST SEC 1
J 0
(1200 -3400);
DISPLAY 0.680851 (1200 -3400);
PAINT MONO (1200 -3400);
DISPLAY INVISIBLE (1200 -3400);
FORCEPROP 2 LASTPIN (1025 -4025) $PN 2
J 2
(1015 -4015);
DISPLAY 0.680851 (1015 -4015);
PAINT MONO (1015 -4015);
FORCEPROP 2 LASTPIN (1025 -3975) $PN 1
J 2
(1015 -3965);
DISPLAY 0.680851 (1015 -3965);
PAINT MONO (1015 -3965);
FORCEPROP 2 LASTPIN (1925 -3875) $PN 3
J 0
(1935 -3865);
DISPLAY 0.680851 (1935 -3865);
PAINT MONO (1935 -3865);
FORCEPROP 2 LASTPIN (1925 -4325) $PN 10
J 0
(1935 -4315);
DISPLAY 0.680851 (1935 -4315);
PAINT MONO (1935 -4315);
FORCEPROP 2 LASTPIN (1925 -3975) $PN 6
J 0
(1935 -3965);
DISPLAY 0.680851 (1935 -3965);
PAINT MONO (1935 -3965);
FORCEPROP 2 LASTPIN (1925 -4025) $PN 7
J 0
(1935 -4015);
DISPLAY 0.680851 (1935 -4015);
PAINT MONO (1935 -4015);
FORCEPROP 2 LASTPIN (1925 -4075) $PN 8
J 0
(1935 -4065);
DISPLAY 0.680851 (1935 -4065);
PAINT MONO (1935 -4065);
FORCEPROP 2 LASTPIN (1925 -4125) $PN 14
J 0
(1935 -4115);
DISPLAY 0.680851 (1935 -4115);
PAINT MONO (1935 -4115);
FORCEPROP 2 LASTPIN (1925 -4175) $PN 15
J 0
(1935 -4165);
DISPLAY 0.680851 (1935 -4165);
PAINT MONO (1935 -4165);
FORCEPROP 2 LASTPIN (1925 -4225) $PN 16
J 0
(1935 -4215);
DISPLAY 0.680851 (1935 -4215);
PAINT MONO (1935 -4215);
FORCEPROP 2 LASTPIN (1025 -4125) $PN 5
J 2
(1015 -4115);
DISPLAY 0.680851 (1015 -4115);
PAINT MONO (1015 -4115);
FORCEPROP 2 LASTPIN (1025 -4175) $PN 4
J 2
(1015 -4165);
DISPLAY 0.680851 (1015 -4165);
PAINT MONO (1015 -4165);
FORCEPROP 2 LASTPIN (1925 -4375) $PN TH
J 0
(1935 -4365);
DISPLAY 0.680851 (1935 -4365);
PAINT MONO (1935 -4365);
FORCEPROP 2 LASTPIN (1025 -4275) $PN 11
J 2
(1015 -4265);
DISPLAY 0.680851 (1015 -4265);
PAINT MONO (1015 -4265);
FORCEPROP 2 LASTPIN (1025 -3875) $PN 9
J 2
(1015 -3865);
DISPLAY 0.680851 (1015 -3865);
PAINT MONO (1015 -3865);
FORCEPROP 2 LASTPIN (1025 -4375) $PN 12
J 2
(1015 -4365);
DISPLAY 0.680851 (1015 -4365);
PAINT MONO (1015 -4365);
FORCEPROP 2 LASTPIN (1025 -4325) $PN 13
J 2
(1015 -4315);
DISPLAY 0.680851 (1015 -4315);
PAINT MONO (1015 -4315);
FORCEPROP 2 LAST PART_TYPE SMLF
J 0
(1200 -3450);
DISPLAY 1.021277 (1200 -3450);
FORCEPROP 1 LAST MATERIAL IC
J 0
(1180 -3818);
DISPLAY 0.723404 (1180 -3818);
PAINT GREEN (1180 -3818);
FORCEPROP 2 LAST VALUE ISL28022FRZ-T
J 0
(1200 -3500);
DISPLAY 1.021277 (1200 -3500);
FORCEPROP 2 LAST SEC_TYPE 
J 0
(1200 -3400);
DISPLAY 1.021277 (1200 -3400);
DISPLAY INVISIBLE (1200 -3400);
FORCEPROP 1 LAST CDS_LMAN_SYM_OUTLINE -300,300,300,-300
J 0
(1475 -4125);
DISPLAY 0.468085 (1475 -4125);
PAINT GREEN (1475 -4125);
DISPLAY INVISIBLE (1475 -4125);
FORCEPROP 1 LAST NEEDS_NO_SIZE TRUE
J 0
(1475 -4125);
DISPLAY 0.723404 (1475 -4125);
PAINT GREEN (1475 -4125);
DISPLAY INVISIBLE (1475 -4125);
FORCEPROP 2 LAST CDS_LIB pure_quanta
J 0
(1475 -4125);
DISPLAY INVISIBLE (1475 -4125);
FORCEPROP 1 LAST PATH I69
J 0
(1475 -4125);
DISPLAY 0.723404 (1475 -4125);
PAINT GREEN (1475 -4125);
DISPLAY INVISIBLE (1475 -4125);
FORCEPROP 1 LAST PART_NUMBER AL028022003
J 0
(1180 -3691);
DISPLAY 0.723404 (1180 -3691);
PAINT GREEN (1180 -3691);
DISPLAY INVISIBLE (1180 -3691);
FORCEADD Q_CAP..1
(75 -2725);
FORCEPROP 1 LAST LOCATION C2021
J 0
(125 -2625);
DISPLAY 0.978723 (125 -2625);
FORCEPROP 0 LAST $SEC 1
J 0
(125 -2575);
DISPLAY 0.680851 (125 -2575);
PAINT MONO (125 -2575);
DISPLAY INVISIBLE (125 -2575);
FORCEPROP 0 LAST CDS_SEC 1
J 0
(125 -2575);
DISPLAY 1.021277 (125 -2575);
DISPLAY INVISIBLE (125 -2575);
FORCEPROP 1 LASTPIN (75 -2625) $PN 1
J 0
(85 -2645);
DISPLAY 0.787234 (85 -2645);
PAINT MONO (85 -2645);
FORCEPROP 1 LASTPIN (75 -2825) $PN 2
J 0
(85 -2845);
DISPLAY 0.787234 (85 -2845);
PAINT MONO (85 -2845);
FORCEPROP 1 LAST TOLERANCE 10%
J 0
(125 -2725);
DISPLAY 0.510638 (125 -2725);
FORCEPROP 1 LAST MATERIAL X7R
J 0
(125 -2750);
DISPLAY 0.510638 (125 -2750);
FORCEPROP 1 LAST PACK_TYPE 0402
J 0
(125 -2800);
DISPLAY 0.510638 (125 -2800);
FORCEPROP 1 LAST VALUE 0.1UF
J 0
(125 -2675);
DISPLAY 0.510638 (125 -2675);
FORCEPROP 1 LAST VOLTAGE 25V
J 0
(125 -2700);
DISPLAY 0.510638 (125 -2700);
FORCEPROP 2 LAST CDS_LIB pure_quanta
J 0
(75 -2725);
DISPLAY INVISIBLE (75 -2725);
FORCEPROP 1 LAST PATH I71
J 0
(125 -2575);
DISPLAY 0.978723 (125 -2575);
PAINT WHITE (125 -2575);
DISPLAY INVISIBLE (125 -2575);
FORCEPROP 1 LAST PART_NUMBER CH4104K1B00
J 0
(125 -2775);
DISPLAY 0.510638 (125 -2775);
DISPLAY INVISIBLE (125 -2775);
FORCEADD Q_CAP..1
(200 -4875);
FORCEPROP 1 LAST LOCATION C2022
J 0
(250 -4775);
DISPLAY 0.978723 (250 -4775);
FORCEPROP 0 LAST $SEC 1
J 0
(250 -4725);
DISPLAY 0.680851 (250 -4725);
PAINT MONO (250 -4725);
DISPLAY INVISIBLE (250 -4725);
FORCEPROP 0 LAST CDS_SEC 1
J 0
(250 -4725);
DISPLAY 1.021277 (250 -4725);
DISPLAY INVISIBLE (250 -4725);
FORCEPROP 1 LASTPIN (200 -4775) $PN 1
J 0
(210 -4795);
DISPLAY 0.787234 (210 -4795);
PAINT MONO (210 -4795);
FORCEPROP 1 LASTPIN (200 -4975) $PN 2
J 0
(210 -4995);
DISPLAY 0.787234 (210 -4995);
PAINT MONO (210 -4995);
FORCEPROP 1 LAST PACK_TYPE 0402
J 0
(250 -4950);
DISPLAY 0.510638 (250 -4950);
FORCEPROP 1 LAST MATERIAL X7R
J 0
(250 -4900);
DISPLAY 0.510638 (250 -4900);
FORCEPROP 1 LAST TOLERANCE 10%
J 0
(250 -4875);
DISPLAY 0.510638 (250 -4875);
FORCEPROP 1 LAST VOLTAGE 25V
J 0
(250 -4850);
DISPLAY 0.510638 (250 -4850);
FORCEPROP 1 LAST VALUE 0.1UF
J 0
(250 -4825);
DISPLAY 0.510638 (250 -4825);
FORCEPROP 2 LAST CDS_LIB pure_quanta
J 0
(200 -4875);
DISPLAY INVISIBLE (200 -4875);
FORCEPROP 1 LAST PATH I72
J 0
(250 -4725);
DISPLAY 0.978723 (250 -4725);
PAINT WHITE (250 -4725);
DISPLAY INVISIBLE (250 -4725);
FORCEPROP 1 LAST PART_NUMBER CH4104K1B00
J 0
(250 -4925);
DISPLAY 0.510638 (250 -4925);
DISPLAY INVISIBLE (250 -4925);
FORCEADD UNIVERSAL_POWER..1
(-1675 -2225);
FORCEPROP 3 LASTPIN (-1675 -2275) SIG_NAME P3V3\g
J 0
(-1665 -2265);
DISPLAY 0.659574 (-1665 -2265);
PAINT MONO (-1665 -2265);
DISPLAY INVISIBLE (-1665 -2265);
FORCEPROP 1 LAST HDL_POWER P3V3
J 1
(-1675 -2175);
DISPLAY 0.872340 (-1675 -2175);
PAINT GREEN (-1675 -2175);
FORCEPROP 2 LAST CDS_LIB pure_quanta_power
J 0
(-1675 -2225);
DISPLAY INVISIBLE (-1675 -2225);
FORCEPROP 1 LAST PATH I76
J 0
(-1625 -2200);
DISPLAY 0.872340 (-1625 -2200);
PAINT AQUA (-1625 -2200);
DISPLAY INVISIBLE (-1625 -2200);
FORCEADD UNIVERSAL_POWER..1
(75 -1025);
FORCEPROP 3 LASTPIN (75 -1075) SIG_NAME P3V3_AUX\g
J 0
(85 -1065);
DISPLAY 0.659574 (85 -1065);
PAINT MONO (85 -1065);
DISPLAY INVISIBLE (85 -1065);
FORCEPROP 1 LAST HDL_POWER P3V3_AUX
J 1
(75 -975);
DISPLAY 0.872340 (75 -975);
PAINT GREEN (75 -975);
FORCEPROP 2 LAST CDS_LIB pure_quanta_power
J 0
(75 -1025);
DISPLAY INVISIBLE (75 -1025);
FORCEPROP 1 LAST PATH I85
J 0
(125 -1000);
DISPLAY 0.872340 (125 -1000);
PAINT AQUA (125 -1000);
DISPLAY INVISIBLE (125 -1000);
FORCEADD Q_RES..2
(75 -1325);
FORCEPROP 1 LAST LOCATION R3623
J 0
(120 -1200);
DISPLAY 0.978723 (120 -1200);
FORCEPROP 0 LAST $SEC 1
J 0
(125 -1150);
DISPLAY 0.680851 (125 -1150);
PAINT MONO (125 -1150);
DISPLAY INVISIBLE (125 -1150);
FORCEPROP 0 LAST CDS_SEC 1
J 0
(125 -1150);
DISPLAY 1.021277 (125 -1150);
DISPLAY INVISIBLE (125 -1150);
FORCEPROP 1 LASTPIN (75 -1225) $PN 1
J 0
(80 -1263);
DISPLAY 0.787234 (80 -1263);
PAINT MONO (80 -1263);
FORCEPROP 1 LASTPIN (75 -1425) $PN 2
J 0
(80 -1415);
DISPLAY 0.787234 (80 -1415);
PAINT MONO (80 -1415);
FORCEPROP 1 LAST VALUE 4.7K
J 0
(120 -1250);
DISPLAY 0.510638 (120 -1250);
FORCEPROP 1 LAST WATTAGE 1/16W
J 0
(115 -1350);
DISPLAY 0.510638 (115 -1350);
FORCEPROP 1 LAST TOLERANCE 1%
J 0
(120 -1300);
DISPLAY 0.510638 (120 -1300);
FORCEPROP 1 LAST MATERIAL CHIP
J 0
(115 -1400);
DISPLAY 0.510638 (115 -1400);
FORCEPROP 1 LAST PACK_TYPE 0402LF
J 0
(115 -1500);
DISPLAY 0.510638 (115 -1500);
FORCEPROP 2 LAST CDS_LIB pure_quanta
J 0
(75 -1325);
DISPLAY INVISIBLE (75 -1325);
FORCEPROP 1 LAST PATH I86
J 0
(125 -1150);
DISPLAY 0.978723 (125 -1150);
PAINT WHITE (125 -1150);
DISPLAY INVISIBLE (125 -1150);
FORCEPROP 1 LAST PART_NUMBER CS24702FB06
J 0
(115 -1450);
DISPLAY 0.510638 (115 -1450);
DISPLAY INVISIBLE (115 -1450);
FORCEADD Q_RES..2
(-225 -1325);
FORCEPROP 1 LAST LOCATION R3621
J 0
(-180 -1200);
DISPLAY 0.978723 (-180 -1200);
FORCEPROP 0 LAST $SEC 1
J 0
(-175 -1150);
DISPLAY 0.680851 (-175 -1150);
PAINT MONO (-175 -1150);
DISPLAY INVISIBLE (-175 -1150);
FORCEPROP 0 LAST CDS_SEC 1
J 0
(-175 -1150);
DISPLAY 1.021277 (-175 -1150);
DISPLAY INVISIBLE (-175 -1150);
FORCEPROP 1 LASTPIN (-225 -1225) $PN 1
J 0
(-220 -1263);
DISPLAY 0.787234 (-220 -1263);
PAINT MONO (-220 -1263);
FORCEPROP 1 LASTPIN (-225 -1425) $PN 2
J 0
(-220 -1415);
DISPLAY 0.787234 (-220 -1415);
PAINT MONO (-220 -1415);
FORCEPROP 1 LAST MATERIAL EMPTY
J 0
(-185 -1400);
DISPLAY 0.510638 (-185 -1400);
PAINT RED (-185 -1400);
FORCEPROP 1 LAST PACK_TYPE 0402LF
J 0
(-185 -1500);
DISPLAY 0.510638 (-185 -1500);
FORCEPROP 1 LAST VALUE 4.7K
J 0
(-180 -1250);
DISPLAY 0.510638 (-180 -1250);
FORCEPROP 1 LAST TOLERANCE 1%
J 0
(-180 -1300);
DISPLAY 0.510638 (-180 -1300);
FORCEPROP 1 LAST WATTAGE 1/16W
J 0
(-185 -1350);
DISPLAY 0.510638 (-185 -1350);
FORCEPROP 2 LAST CDS_LIB pure_quanta
J 0
(-225 -1325);
DISPLAY INVISIBLE (-225 -1325);
FORCEPROP 1 LAST PATH I87
J 0
(-175 -1150);
DISPLAY 0.978723 (-175 -1150);
PAINT WHITE (-175 -1150);
DISPLAY INVISIBLE (-175 -1150);
FORCEPROP 1 LAST PART_NUMBER CS24702FB06
J 0
(-185 -1450);
DISPLAY 0.510638 (-185 -1450);
DISPLAY INVISIBLE (-185 -1450);
FORCEADD UNIVERSAL_POWER..1
(125 -3225);
FORCEPROP 3 LASTPIN (125 -3275) SIG_NAME P3V3_AUX\g
J 0
(135 -3265);
DISPLAY 0.659574 (135 -3265);
PAINT MONO (135 -3265);
DISPLAY INVISIBLE (135 -3265);
FORCEPROP 1 LAST HDL_POWER P3V3_AUX
J 1
(125 -3175);
DISPLAY 0.872340 (125 -3175);
PAINT GREEN (125 -3175);
FORCEPROP 2 LAST CDS_LIB pure_quanta_power
J 0
(125 -3225);
DISPLAY INVISIBLE (125 -3225);
FORCEPROP 1 LAST PATH I88
J 0
(175 -3200);
DISPLAY 0.872340 (175 -3200);
PAINT AQUA (175 -3200);
DISPLAY INVISIBLE (175 -3200);
FORCEADD Q_RES..2
(125 -3525);
FORCEPROP 1 LAST LOCATION R3624
J 0
(170 -3400);
DISPLAY 0.978723 (170 -3400);
FORCEPROP 0 LAST $SEC 1
J 0
(175 -3350);
DISPLAY 0.680851 (175 -3350);
PAINT MONO (175 -3350);
DISPLAY INVISIBLE (175 -3350);
FORCEPROP 0 LAST CDS_SEC 1
J 0
(175 -3350);
DISPLAY 1.021277 (175 -3350);
DISPLAY INVISIBLE (175 -3350);
FORCEPROP 1 LASTPIN (125 -3425) $PN 1
J 0
(130 -3463);
DISPLAY 0.787234 (130 -3463);
PAINT MONO (130 -3463);
FORCEPROP 1 LASTPIN (125 -3625) $PN 2
J 0
(130 -3615);
DISPLAY 0.787234 (130 -3615);
PAINT MONO (130 -3615);
FORCEPROP 1 LAST PACK_TYPE 0402LF
J 0
(165 -3700);
DISPLAY 0.510638 (165 -3700);
FORCEPROP 1 LAST MATERIAL CHIP
J 0
(165 -3600);
DISPLAY 0.510638 (165 -3600);
FORCEPROP 1 LAST VALUE 4.7K
J 0
(170 -3450);
DISPLAY 0.510638 (170 -3450);
FORCEPROP 1 LAST TOLERANCE 1%
J 0
(170 -3500);
DISPLAY 0.510638 (170 -3500);
FORCEPROP 1 LAST WATTAGE 1/16W
J 0
(165 -3550);
DISPLAY 0.510638 (165 -3550);
FORCEPROP 2 LAST CDS_LIB pure_quanta
J 0
(125 -3525);
DISPLAY INVISIBLE (125 -3525);
FORCEPROP 1 LAST PATH I89
J 0
(175 -3350);
DISPLAY 0.978723 (175 -3350);
PAINT WHITE (175 -3350);
DISPLAY INVISIBLE (175 -3350);
FORCEPROP 1 LAST PART_NUMBER CS24702FB06
J 0
(165 -3650);
DISPLAY 0.510638 (165 -3650);
DISPLAY INVISIBLE (165 -3650);
FORCEADD Q_RES..2
(-175 -3525);
FORCEPROP 1 LAST LOCATION R3622
J 0
(-130 -3400);
DISPLAY 0.978723 (-130 -3400);
FORCEPROP 0 LAST $SEC 1
J 0
(-125 -3350);
DISPLAY 0.680851 (-125 -3350);
PAINT MONO (-125 -3350);
DISPLAY INVISIBLE (-125 -3350);
FORCEPROP 0 LAST CDS_SEC 1
J 0
(-125 -3350);
DISPLAY 1.021277 (-125 -3350);
DISPLAY INVISIBLE (-125 -3350);
FORCEPROP 1 LASTPIN (-175 -3425) $PN 1
J 0
(-170 -3463);
DISPLAY 0.787234 (-170 -3463);
PAINT MONO (-170 -3463);
FORCEPROP 1 LASTPIN (-175 -3625) $PN 2
J 0
(-170 -3615);
DISPLAY 0.787234 (-170 -3615);
PAINT MONO (-170 -3615);
FORCEPROP 1 LAST WATTAGE 1/16W
J 0
(-135 -3550);
DISPLAY 0.510638 (-135 -3550);
FORCEPROP 1 LAST TOLERANCE 1%
J 0
(-130 -3500);
DISPLAY 0.510638 (-130 -3500);
FORCEPROP 1 LAST MATERIAL CHIP
J 0
(-135 -3600);
DISPLAY 0.510638 (-135 -3600);
FORCEPROP 1 LAST PACK_TYPE 0402LF
J 0
(-135 -3700);
DISPLAY 0.510638 (-135 -3700);
FORCEPROP 1 LAST VALUE 4.7K
J 0
(-130 -3450);
DISPLAY 0.510638 (-130 -3450);
FORCEPROP 2 LAST CDS_LIB pure_quanta
J 0
(-175 -3525);
DISPLAY INVISIBLE (-175 -3525);
FORCEPROP 1 LAST PATH I90
J 0
(-125 -3350);
DISPLAY 0.978723 (-125 -3350);
PAINT WHITE (-125 -3350);
DISPLAY INVISIBLE (-125 -3350);
FORCEPROP 1 LAST PART_NUMBER CS24702FB06
J 0
(-135 -3650);
DISPLAY 0.510638 (-135 -3650);
DISPLAY INVISIBLE (-135 -3650);
FORCEADD Q_RES..1
(-2150 -2375);
FORCEPROP 1 LAST LOCATION R3634
J 0
(-2200 -2325);
DISPLAY 0.978723 (-2200 -2325);
FORCEPROP 0 LAST $SEC 1
J 0
(-2200 -2275);
DISPLAY 0.680851 (-2200 -2275);
PAINT MONO (-2200 -2275);
DISPLAY INVISIBLE (-2200 -2275);
FORCEPROP 0 LAST CDS_SEC 1
J 0
(-2200 -2275);
DISPLAY 1.021277 (-2200 -2275);
DISPLAY INVISIBLE (-2200 -2275);
FORCEPROP 1 LASTPIN (-2250 -2375) $PN 1
J 0
(-2238 -2363);
DISPLAY 0.787234 (-2238 -2363);
PAINT MONO (-2238 -2363);
FORCEPROP 1 LASTPIN (-2050 -2375) $PN 2
J 0
(-2088 -2363);
DISPLAY 0.787234 (-2088 -2363);
PAINT MONO (-2088 -2363);
FORCEPROP 1 LAST PACK_TYPE 2512LF
J 0
(-2075 -2475);
DISPLAY 0.510638 (-2075 -2475);
FORCEPROP 1 LAST TOLERANCE 1%
J 0
(-2150 -2475);
DISPLAY 0.510638 (-2150 -2475);
FORCEPROP 1 LAST VALUE 0.002
J 2
(-2175 -2475);
DISPLAY 0.510638 (-2175 -2475);
FORCEPROP 1 LAST WATTAGE 2W
J 2
(-2175 -2525);
DISPLAY 0.510638 (-2175 -2525);
FORCEPROP 1 LAST MATERIAL CHIP
J 0
(-2150 -2525);
DISPLAY 0.510638 (-2150 -2525);
FORCEPROP 2 LAST CDS_LIB pure_quanta
J 0
(-2150 -2375);
DISPLAY INVISIBLE (-2150 -2375);
FORCEPROP 1 LAST PATH I92
J 0
(-2200 -2225);
DISPLAY 0.978723 (-2200 -2225);
PAINT WHITE (-2200 -2225);
DISPLAY INVISIBLE (-2200 -2225);
FORCEPROP 1 LAST PART_NUMBER CS+002AFR06
J 0
(-2275 -2425);
DISPLAY 0.510638 (-2275 -2425);
DISPLAY INVISIBLE (-2275 -2425);
FORCEADD Q_RES..1
(-2050 -4525);
FORCEPROP 1 LAST LOCATION R3635
J 0
(-2100 -4475);
DISPLAY 0.978723 (-2100 -4475);
FORCEPROP 0 LAST $SEC 1
J 0
(-2100 -4425);
DISPLAY 0.680851 (-2100 -4425);
PAINT MONO (-2100 -4425);
DISPLAY INVISIBLE (-2100 -4425);
FORCEPROP 0 LAST CDS_SEC 1
J 0
(-2100 -4425);
DISPLAY 1.021277 (-2100 -4425);
DISPLAY INVISIBLE (-2100 -4425);
FORCEPROP 1 LASTPIN (-2150 -4525) $PN 1
J 0
(-2138 -4513);
DISPLAY 0.787234 (-2138 -4513);
PAINT MONO (-2138 -4513);
FORCEPROP 1 LASTPIN (-1950 -4525) $PN 2
J 0
(-1988 -4513);
DISPLAY 0.787234 (-1988 -4513);
PAINT MONO (-1988 -4513);
FORCEPROP 1 LAST TOLERANCE 1%
J 0
(-2050 -4625);
DISPLAY 0.510638 (-2050 -4625);
FORCEPROP 1 LAST VALUE 0.002
J 2
(-2075 -4625);
DISPLAY 0.510638 (-2075 -4625);
FORCEPROP 1 LAST WATTAGE 2W
J 2
(-2075 -4675);
DISPLAY 0.510638 (-2075 -4675);
FORCEPROP 1 LAST PACK_TYPE 2512LF
J 0
(-1975 -4625);
DISPLAY 0.510638 (-1975 -4625);
FORCEPROP 1 LAST MATERIAL CHIP
J 0
(-2050 -4675);
DISPLAY 0.510638 (-2050 -4675);
FORCEPROP 2 LAST CDS_LIB pure_quanta
J 0
(-2050 -4525);
DISPLAY INVISIBLE (-2050 -4525);
FORCEPROP 1 LAST PATH I93
J 0
(-2100 -4375);
DISPLAY 0.978723 (-2100 -4375);
PAINT WHITE (-2100 -4375);
DISPLAY INVISIBLE (-2100 -4375);
FORCEPROP 1 LAST PART_NUMBER CS+002AFR06
J 0
(-2175 -4575);
DISPLAY 0.510638 (-2175 -4575);
DISPLAY INVISIBLE (-2175 -4575);
FORCEADD ISL28022FRZT..1
(1775 125);
FORCEPROP 1 LAST LOCATION U263
J 0
(1480 706);
DISPLAY 0.723404 (1480 706);
PAINT GREEN (1480 706);
FORCEPROP 2 LAST SEC 1
J 0
(1500 850);
DISPLAY 0.680851 (1500 850);
PAINT MONO (1500 850);
DISPLAY INVISIBLE (1500 850);
FORCEPROP 2 LASTPIN (1325 225) $PN 2
J 2
(1315 235);
DISPLAY 0.680851 (1315 235);
PAINT MONO (1315 235);
FORCEPROP 2 LASTPIN (1325 275) $PN 1
J 2
(1315 285);
DISPLAY 0.680851 (1315 285);
PAINT MONO (1315 285);
FORCEPROP 2 LASTPIN (2225 375) $PN 3
J 0
(2235 385);
DISPLAY 0.680851 (2235 385);
PAINT MONO (2235 385);
FORCEPROP 2 LASTPIN (2225 -75) $PN 10
J 0
(2235 -65);
DISPLAY 0.680851 (2235 -65);
PAINT MONO (2235 -65);
FORCEPROP 2 LASTPIN (2225 275) $PN 6
J 0
(2235 285);
DISPLAY 0.680851 (2235 285);
PAINT MONO (2235 285);
FORCEPROP 2 LASTPIN (2225 225) $PN 7
J 0
(2235 235);
DISPLAY 0.680851 (2235 235);
PAINT MONO (2235 235);
FORCEPROP 2 LASTPIN (2225 175) $PN 8
J 0
(2235 185);
DISPLAY 0.680851 (2235 185);
PAINT MONO (2235 185);
FORCEPROP 2 LASTPIN (2225 125) $PN 14
J 0
(2235 135);
DISPLAY 0.680851 (2235 135);
PAINT MONO (2235 135);
FORCEPROP 2 LASTPIN (2225 75) $PN 15
J 0
(2235 85);
DISPLAY 0.680851 (2235 85);
PAINT MONO (2235 85);
FORCEPROP 2 LASTPIN (2225 25) $PN 16
J 0
(2235 35);
DISPLAY 0.680851 (2235 35);
PAINT MONO (2235 35);
FORCEPROP 2 LASTPIN (1325 125) $PN 5
J 2
(1315 135);
DISPLAY 0.680851 (1315 135);
PAINT MONO (1315 135);
FORCEPROP 2 LASTPIN (1325 75) $PN 4
J 2
(1315 85);
DISPLAY 0.680851 (1315 85);
PAINT MONO (1315 85);
FORCEPROP 2 LASTPIN (2225 -125) $PN TH
J 0
(2235 -115);
DISPLAY 0.680851 (2235 -115);
PAINT MONO (2235 -115);
FORCEPROP 2 LASTPIN (1325 -25) $PN 11
J 2
(1315 -15);
DISPLAY 0.680851 (1315 -15);
PAINT MONO (1315 -15);
FORCEPROP 2 LASTPIN (1325 375) $PN 9
J 2
(1315 385);
DISPLAY 0.680851 (1315 385);
PAINT MONO (1315 385);
FORCEPROP 2 LASTPIN (1325 -125) $PN 12
J 2
(1315 -115);
DISPLAY 0.680851 (1315 -115);
PAINT MONO (1315 -115);
FORCEPROP 2 LASTPIN (1325 -75) $PN 13
J 2
(1315 -65);
DISPLAY 0.680851 (1315 -65);
PAINT MONO (1315 -65);
FORCEPROP 2 LAST VALUE ISL28022FRZ-T
J 0
(1500 750);
DISPLAY 1.021277 (1500 750);
FORCEPROP 2 LAST PART_TYPE SMLF
J 0
(1500 800);
DISPLAY 1.021277 (1500 800);
FORCEPROP 1 LAST MATERIAL IC
J 0
(1480 432);
DISPLAY 0.723404 (1480 432);
PAINT GREEN (1480 432);
FORCEPROP 2 LAST SEC_TYPE 
J 0
(1500 850);
DISPLAY 1.021277 (1500 850);
DISPLAY INVISIBLE (1500 850);
FORCEPROP 1 LAST CDS_LMAN_SYM_OUTLINE -300,300,300,-300
J 0
(1775 125);
DISPLAY 0.468085 (1775 125);
PAINT GREEN (1775 125);
DISPLAY INVISIBLE (1775 125);
FORCEPROP 1 LAST NEEDS_NO_SIZE TRUE
J 0
(1775 125);
DISPLAY 0.723404 (1775 125);
PAINT GREEN (1775 125);
DISPLAY INVISIBLE (1775 125);
FORCEPROP 2 LAST CDS_LIB pure_quanta
J 0
(1775 125);
DISPLAY INVISIBLE (1775 125);
FORCEPROP 1 LAST PATH I94
J 0
(1775 125);
DISPLAY 0.723404 (1775 125);
PAINT GREEN (1775 125);
DISPLAY INVISIBLE (1775 125);
FORCEPROP 1 LAST PART_NUMBER AL028022003
J 0
(1480 559);
DISPLAY 0.723404 (1480 559);
PAINT GREEN (1480 559);
DISPLAY INVISIBLE (1480 559);
FORCEADD OFFPAGE..2
(4825 375);
FORCEPROP 2 LAST $XR1 82 
J 0
(5134 375);
DISPLAY 0.638298 (5134 375);
PAINT MONO (5134 375);
FORCEPROP 2 LAST $XR0 358 
J 0
(5014 375);
DISPLAY 0.638298 (5014 375);
PAINT MONO (5014 375);
FORCEPROP 2 LAST CDS_LIB standard
J 0
(4825 375);
DISPLAY INVISIBLE (4825 375);
FORCEPROP 1 LAST OFFPAGE TRUE
J 0
(5150 250);
DISPLAY 0.872340 (5150 250);
DISPLAY INVISIBLE (5150 250);
FORCEPROP 1 LAST COMMENT_BODY TRUE
J 0
(4780 280);
DISPLAY 0.872340 (4780 280);
PAINT GREEN (4780 280);
DISPLAY INVISIBLE (4780 280);
FORCEPROP 2 LAST PATH I95
J 0
(5025 425);
DISPLAY 1.021277 (5025 425);
DISPLAY INVISIBLE (5025 425);
FORCEADD Q_RES..1
(3375 375);
FORCEPROP 1 LAST LOCATION R3559
J 0
(3200 375);
DISPLAY 0.510638 (3200 375);
FORCEPROP 0 LAST $SEC 1
J 0
(3675 425);
DISPLAY 0.680851 (3675 425);
PAINT MONO (3675 425);
DISPLAY INVISIBLE (3675 425);
FORCEPROP 0 LAST CDS_SEC 1
J 0
(3675 425);
DISPLAY 1.021277 (3675 425);
DISPLAY INVISIBLE (3675 425);
FORCEPROP 1 LASTPIN (3275 375) $PN 1
J 0
(3287 387);
DISPLAY 0.787234 (3287 387);
PAINT MONO (3287 387);
FORCEPROP 1 LASTPIN (3475 375) $PN 2
J 0
(3437 387);
DISPLAY 0.787234 (3437 387);
PAINT MONO (3437 387);
FORCEPROP 1 LAST MATERIAL CHIP
J 0
(3550 375);
DISPLAY 0.574468 (3550 375);
FORCEPROP 1 LAST VALUE 0
J 2
(3525 375);
DISPLAY 0.574468 (3525 375);
FORCEPROP 1 LAST PACK_TYPE 0402LF
J 0
(3675 375);
DISPLAY 0.574468 (3675 375);
FORCEPROP 2 LAST CDS_LIB pure_quanta
J 0
(3375 375);
DISPLAY INVISIBLE (3375 375);
FORCEPROP 1 LAST TOLERANCE 5%
J 0
(3175 300);
DISPLAY 0.723404 (3175 300);
PAINT SKYBLUE (3175 300);
DISPLAY INVISIBLE (3175 300);
FORCEPROP 1 LAST WATTAGE 1/16W
J 2
(3450 300);
DISPLAY 0.723404 (3450 300);
PAINT SKYBLUE (3450 300);
DISPLAY INVISIBLE (3450 300);
FORCEPROP 1 LAST PATH I96
J 0
(3325 525);
DISPLAY 0.978723 (3325 525);
PAINT WHITE (3325 525);
DISPLAY INVISIBLE (3325 525);
FORCEPROP 1 LAST PART_NUMBER CS00002JB13
J 0
(3100 250);
DISPLAY 0.723404 (3100 250);
PAINT WHITE (3100 250);
DISPLAY INVISIBLE (3100 250);
FORCEADD UNIVERSAL_POWER..1
(1275 1125);
FORCEPROP 3 LASTPIN (1275 1075) SIG_NAME P3V3_AUX\g
J 0
(1285 1085);
DISPLAY 0.659574 (1285 1085);
PAINT MONO (1285 1085);
DISPLAY INVISIBLE (1285 1085);
FORCEPROP 1 LAST HDL_POWER P3V3_AUX
J 1
(1275 1175);
DISPLAY 0.872340 (1275 1175);
PAINT GREEN (1275 1175);
FORCEPROP 2 LAST CDS_LIB pure_quanta_power
J 0
(1275 1125);
DISPLAY INVISIBLE (1275 1125);
FORCEPROP 1 LAST PATH I97
J 0
(1325 1150);
DISPLAY 0.872340 (1325 1150);
PAINT AQUA (1325 1150);
DISPLAY INVISIBLE (1325 1150);
FORCEADD Q_CAP..1
(1025 725);
FORCEPROP 1 LAST LOCATION C2012
J 0
(1075 825);
DISPLAY 0.978723 (1075 825);
FORCEPROP 0 LAST $SEC 1
J 0
(1075 875);
DISPLAY 0.680851 (1075 875);
PAINT MONO (1075 875);
DISPLAY INVISIBLE (1075 875);
FORCEPROP 0 LAST CDS_SEC 1
J 0
(1075 875);
DISPLAY 1.021277 (1075 875);
DISPLAY INVISIBLE (1075 875);
FORCEPROP 1 LASTPIN (1025 825) $PN 1
J 0
(1035 805);
DISPLAY 0.787234 (1035 805);
PAINT MONO (1035 805);
FORCEPROP 1 LASTPIN (1025 625) $PN 2
J 0
(1035 605);
DISPLAY 0.787234 (1035 605);
PAINT MONO (1035 605);
FORCEPROP 1 LAST PACK_TYPE 0402
J 0
(1075 575);
DISPLAY 0.638298 (1075 575);
FORCEPROP 1 LAST VALUE 0.1UF
J 0
(1075 775);
DISPLAY 0.638298 (1075 775);
FORCEPROP 1 LAST VOLTAGE 25V
J 0
(1075 725);
DISPLAY 0.638298 (1075 725);
FORCEPROP 1 LAST TOLERANCE 10%
J 0
(1075 675);
DISPLAY 0.638298 (1075 675);
FORCEPROP 1 LAST MATERIAL X7R
J 0
(1075 625);
DISPLAY 0.638298 (1075 625);
FORCEPROP 2 LAST CDS_LIB pure_quanta
J 0
(1025 725);
DISPLAY INVISIBLE (1025 725);
FORCEPROP 1 LAST PATH I98
J 0
(1075 875);
DISPLAY 0.978723 (1075 875);
PAINT WHITE (1075 875);
DISPLAY INVISIBLE (1075 875);
FORCEPROP 1 LAST PART_NUMBER CH4104K1B00
J 0
(1075 575);
DISPLAY 0.808511 (1075 575);
DISPLAY INVISIBLE (1075 575);
FORCEADD UNIVERSAL_GND..1
(1025 450);
FORCEPROP 3 LASTPIN (1025 500) SIG_NAME GND\g
J 0
(1035 510);
DISPLAY 0.659574 (1035 510);
PAINT MONO (1035 510);
DISPLAY INVISIBLE (1035 510);
FORCEPROP 2 LAST CDS_LIB pure_quanta_power
J 0
(1025 450);
DISPLAY INVISIBLE (1025 450);
FORCEPROP 1 LAST HDL_POWER GND
J 1
(1050 375);
DISPLAY 0.872340 (1050 375);
PAINT GREEN (1050 375);
DISPLAY INVISIBLE (1050 375);
FORCEPROP 1 LAST PATH I99
J 0
(1100 450);
DISPLAY 0.872340 (1100 450);
PAINT AQUA (1100 450);
DISPLAY INVISIBLE (1100 450);
FORCEADD DNS..2
(-500 525);
PAINT RED (-500 525);
FORCEPROP 2 LAST CDS_LIB mstr_misc
J 0
(-500 525);
DISPLAY INVISIBLE (-500 525);
FORCEPROP 1 LAST COMMENT_BODY TRUE
R 1
J 0
(-425 300);
DISPLAY 0.872340 (-425 300);
PAINT GREEN (-425 300);
DISPLAY INVISIBLE (-425 300);
FORCEADD DNS..2
(-1025 -1675);
PAINT RED (-1025 -1675);
FORCEPROP 2 LAST CDS_LIB mstr_misc
J 0
(-1025 -1675);
DISPLAY INVISIBLE (-1025 -1675);
FORCEPROP 1 LAST COMMENT_BODY TRUE
R 1
J 0
(-950 -1900);
DISPLAY 0.872340 (-950 -1900);
PAINT GREEN (-950 -1900);
DISPLAY INVISIBLE (-950 -1900);
FORCEADD DNS..2
(-225 -1350);
PAINT RED (-225 -1350);
FORCEPROP 2 LAST CDS_LIB mstr_misc
J 0
(-225 -1350);
DISPLAY INVISIBLE (-225 -1350);
FORCEPROP 1 LAST COMMENT_BODY TRUE
R 1
J 0
(-150 -1575);
DISPLAY 0.872340 (-150 -1575);
PAINT GREEN (-150 -1575);
DISPLAY INVISIBLE (-150 -1575);
FORCEADD DNS..2
(-950 -3925);
PAINT RED (-950 -3925);
FORCEPROP 2 LAST CDS_LIB mstr_misc
J 0
(-950 -3925);
DISPLAY INVISIBLE (-950 -3925);
FORCEPROP 1 LAST COMMENT_BODY TRUE
R 1
J 0
(-875 -4150);
DISPLAY 0.872340 (-875 -4150);
PAINT GREEN (-875 -4150);
DISPLAY INVISIBLE (-875 -4150);
FORCEADD DNS..2
(-950 -3850);
PAINT RED (-950 -3850);
FORCEPROP 2 LAST CDS_LIB mstr_misc
J 0
(-950 -3850);
DISPLAY INVISIBLE (-950 -3850);
FORCEPROP 1 LAST COMMENT_BODY TRUE
R 1
J 0
(-875 -4075);
DISPLAY 0.872340 (-875 -4075);
PAINT GREEN (-875 -4075);
DISPLAY INVISIBLE (-875 -4075);
FORCEADD BOM_NOTE..1
(-3575 -1000);
FORCEPROP 0 LAST S1 POWER MONITOR WILL CHANGE TO AL000230001
J 0
(-3725 -1150);
DISPLAY 1.595745 (-3725 -1150);
PAINT SKYBLUE (-3725 -1150);
FORCEPROP 2 LAST CDS_LIB pure_quanta_power
J 0
(-3575 -1000);
DISPLAY INVISIBLE (-3575 -1000);
FORCEPROP 1 LAST COMMENT_BODY TRUE
J 0
(-3550 -900);
DISPLAY 0.978723 (-3550 -900);
DISPLAY INVISIBLE (-3550 -900);
FORCEADD QUANTA_TITLE_BLOCK_C..1
(5375 -5375);
FORCEPROP 0 LAST CDS_CON_LAST_MODIFIED Thu Sep 14 16:12:31 2023
J 0
(3490 -5360);
DISPLAY INVISIBLE (3490 -5360);
FORCEPROP 1 LAST CUSTOM_TXT_CDS <CON_LAST_MODIFIED>
J 0
(3490 -5360);
DISPLAY 0.978723 (3490 -5360);
FORCEPROP 2 LAST CUSTOM_TXT_CDS <XR_PAGE_TITLE>
J 0
(-2515 -125);
DISPLAY 0.638298 (-2515 -125);
PAINT PINK (-2515 -125);
DISPLAY INVISIBLE (-2515 -125);
FORCEPROP 1 LAST CUSTOM_TXT_CDS <NAME_2>
J 0
(2200 -5325);
FORCEPROP 1 LAST CUSTOM_TXT_CDS <NAME_1>
J 0
(2200 -5200);
FORCEPROP 1 LAST CUSTOM_TXT_CDS <Q_NUMBER>
J 0
(3972 -5272);
DISPLAY 1.212766 (3972 -5272);
FORCEPROP 1 LAST CUSTOM_TXT_CDS <Q_PROJ>
J 0
(2993 -5273);
DISPLAY 1.212766 (2993 -5273);
FORCEPROP 1 LAST CUSTOM_TXT_CDS <Q_REV>
J 0
(5191 -5272);
DISPLAY 1.212766 (5191 -5272);
FORCEPROP 1 LAST CUSTOM_TXT_CDS <CON_PAGE_NUM> OF <CON_TOTAL_PAGES>
J 0
(4929 -5357);
DISPLAY 0.978723 (4929 -5357);
FORCEPROP 1 LAST Q_TITLE POWER MONITOR (2/4)
J 0
(-3850 -5300);
DISPLAY 2.446809 (-3850 -5300);
PAINT GREEN (-3850 -5300);
FORCEPROP 2 LAST PAGE_BORDER TRUE
J 0
(-2515 -125);
DISPLAY 0.638298 (-2515 -125);
PAINT PINK (-2515 -125);
DISPLAY INVISIBLE (-2515 -125);
FORCEPROP 1 LAST CDS_LMAN_SYM_OUTLINE -9475,6775,100,-125
J 0
(5375 -5375);
DISPLAY 0.468085 (5375 -5375);
PAINT GREEN (5375 -5375);
DISPLAY INVISIBLE (5375 -5375);
FORCEPROP 2 LAST CDS_LIB pure_quanta
J 0
(5375 -5375);
DISPLAY INVISIBLE (5375 -5375);
FORCEPROP 2 LAST CDS_XR_PAGE_TITLE CR-238 : @T6G_MB_LIB.T6G(SCH_1):PAGE238
J 0
(-2515 -125);
DISPLAY 0.638298 (-2515 -125);
PAINT PINK (-2515 -125);
DISPLAY INVISIBLE (-2515 -125);
FORCEPROP 1 LAST Q_DEPT BU9
J 1
(1612 -5326);
DISPLAY 1.957447 (1612 -5326);
PAINT GREEN (1612 -5326);
DISPLAY INVISIBLE (1612 -5326);
FORCEPROP 1 LAST COMMENT_BODY TRUE
J 0
(5387 -5388);
DISPLAY 0.978723 (5387 -5388);
PAINT GREEN (5387 -5388);
DISPLAY INVISIBLE (5387 -5388);
WIRE 16 -1 (-1650 200)(-1650 75);
WIRE 16 -1 (2675 -3325)(2675 -3275);
WIRE 16 -1 (2600 -1175)(2600 -1125);
WIRE 16 -1 (3175 925)(3175 975);
WIRE 16 -1 (-2075 -1900)(-2075 -2025);
WIRE 16 -1 (600 -1475)(600 -1600);
WIRE 16 -1 (-1950 -4050)(-1950 -4175);
WIRE 16 -1 (725 -3625)(725 -3750);
WIRE 16 -1 (1025 625)(1025 500);
WIRE 16 2175 (2375 -900)(3050 -900);
WIRE 16 2175 (2375 -900)(2375 -1500);
WIRE 16 2175 (3050 -900)(3050 -1500);
WIRE 16 2175 (2375 -1500)(3050 -1500);
WIRE 16 -1 (2900 -1725)(3925 -1725);
FORCEPROP 2 LAST SIG_NAME M2_0_P3V3_ADC_ALERT
J 0
(3290 -1715);
DISPLAY 0.638298 (3290 -1715);
PAINT WHITE (3290 -1715);
WIRE 16 2175 (2475 -3075)(3150 -3075);
WIRE 16 2175 (2475 -3075)(2475 -3675);
WIRE 16 2175 (3150 -3075)(3150 -3675);
WIRE 16 2175 (2475 -3675)(3150 -3675);
WIRE 16 -1 (775 -2850)(775 -2225);
WIRE 16 -1 (775 -2850)(75 -2850);
FORCEPROP 2 LAST SIG_NAME VSENSE_P12V_INA230_4_INN
J 0
(115 -2840);
DISPLAY 0.510638 (115 -2840);
PAINT WHITE (115 -2840);
FORCEPROP 2 LASTPROP $XRERR UNIQUE?
J 0
(-125 -2840);
DISPLAY 0.638298 (-125 -2840);
PAINT MONO (-125 -2840);
DISPLAY INVISIBLE (-125 -2840);
WIRE 16 -1 (775 -2225)(900 -2225);
WIRE 16 -1 (75 -2825)(75 -2850);
WIRE 16 -1 (-175 -2850)(75 -2850);
WIRE 16 -1 (900 -2125)(-1825 -2125);
WIRE 16 -1 (-1825 -1575)(-1825 -2125);
WIRE 16 -1 (-1825 -1525)(-1825 -1575);
WIRE 16 -1 (-2075 -1575)(-1825 -1575);
WIRE 16 -1 (-2075 -1700)(-2075 -1575);
WIRE 16 2175 (2975 575)(3650 575);
WIRE 16 2175 (2975 1175)(2975 575);
WIRE 16 2175 (3650 1175)(3650 575);
WIRE 16 2175 (2975 1175)(3650 1175);
WIRE 16 -1 (3475 375)(4775 375);
FORCEPROP 2 LAST SIG_NAME OCP_V3_2_P3V3_P12V_ADC_R_ALERT
J 0
(3865 385);
DISPLAY 0.638298 (3865 385);
PAINT WHITE (3865 385);
WIRE 16 -1 (3175 725)(3175 375);
WIRE 16 -1 (3175 375)(3275 375);
WIRE 16 -1 (2225 375)(3175 375);
FORCEPROP 2 LAST SIG_NAME OCP_V3_2_P3V3_ADC_ALERT_R
J 0
(2365 385);
DISPLAY 0.638298 (2365 385);
PAINT WHITE (2365 385);
FORCEPROP 2 LASTPROP $XRERR UNIQUE?
J 0
(2125 385);
DISPLAY 0.638298 (2125 385);
PAINT MONO (2125 385);
DISPLAY INVISIBLE (2125 385);
WIRE 16 -1 (2225 275)(2850 275);
FORCEPROP 2 LAST SIG_NAME NC_INA230_3_NC0
J 0
(2365 285);
DISPLAY 0.638298 (2365 285);
PAINT WHITE (2365 285);
FORCEPROP 2 LASTPROP $XRERR UNIQUE?
J 0
(2880 275);
DISPLAY 0.638298 (2880 275);
PAINT MONO (2880 275);
DISPLAY INVISIBLE (2880 275);
WIRE 16 -1 (2225 225)(2850 225);
FORCEPROP 2 LAST SIG_NAME NC_INA230_3_NC1
J 0
(2365 235);
DISPLAY 0.638298 (2365 235);
PAINT WHITE (2365 235);
FORCEPROP 2 LASTPROP $XRERR UNIQUE?
J 0
(2880 225);
DISPLAY 0.638298 (2880 225);
PAINT MONO (2880 225);
DISPLAY INVISIBLE (2880 225);
WIRE 16 -1 (-2325 -5000)(-250 -5000);
WIRE 16 -1 (-2325 -4525)(-2325 -5000);
WIRE 16 -1 (-2150 -4525)(-2325 -4525);
WIRE 16 -1 (-2325 -4525)(-2625 -4525);
WIRE 16 -1 (-2625 -4525)(-2625 -4425);
WIRE 16 -1 (1025 -4275)(-1700 -4275);
WIRE 16 -1 (-1700 -3725)(-1700 -4275);
WIRE 16 -1 (-1700 -3675)(-1700 -3725);
WIRE 16 -1 (-1950 -3725)(-1700 -3725);
WIRE 16 -1 (-1950 -3850)(-1950 -3725);
WIRE 16 -1 (-1325 -4175)(-275 -4175);
FORCEPROP 2 LAST SIG_NAME SMB_INA230_5_3V3AUX_SDA_R
J 0
(-1260 -4165);
DISPLAY 0.680851 (-1260 -4165);
PAINT WHITE (-1260 -4165);
WIRE 16 -1 (1025 950)(1275 950);
WIRE 16 -1 (1025 825)(1025 950);
WIRE 16 -1 (1275 1075)(1275 950);
WIRE 16 -1 (1275 950)(1275 375);
WIRE 16 -1 (1275 375)(1325 375);
WIRE 16 -1 (125 -3275)(125 -3350);
WIRE 16 -1 (125 -3350)(125 -3425);
WIRE 16 -1 (-175 -3350)(125 -3350);
WIRE 16 -1 (-175 -3425)(-175 -3350);
WIRE 16 -1 (75 -1075)(75 -1150);
WIRE 16 -1 (75 -1150)(75 -1225);
WIRE 16 -1 (-225 -1150)(75 -1150);
WIRE 16 -1 (-225 -1225)(-225 -1150);
WIRE 16 -1 (975 -3875)(1025 -3875);
WIRE 16 -1 (975 -3300)(975 -3875);
WIRE 16 -1 (975 -3175)(975 -3300);
WIRE 16 -1 (725 -3300)(975 -3300);
WIRE 16 -1 (725 -3425)(725 -3300);
WIRE 16 -1 (1925 -4325)(2050 -4325);
WIRE 16 -1 (2050 -4325)(2050 -4375);
WIRE 16 -1 (1925 -4375)(2050 -4375);
WIRE 16 -1 (2050 -4375)(2050 -4725);
WIRE 16 -1 (-1400 -3925)(-1075 -3925);
WIRE 16 -1 (-1400 -3850)(-1400 -3925);
WIRE 16 -1 (-1400 -4000)(-1400 -3925);
WIRE 16 -1 (-1075 -3850)(-1400 -3850);
WIRE 16 -1 (600 -1150)(850 -1150);
WIRE 16 -1 (600 -1275)(600 -1150);
WIRE 16 -1 (850 -1025)(850 -1150);
WIRE 16 -1 (850 -1150)(850 -1725);
WIRE 16 -1 (850 -1725)(900 -1725);
WIRE 16 -1 (1800 -2175)(1925 -2175);
WIRE 16 -1 (1925 -2175)(1925 -2225);
WIRE 16 -1 (1800 -2225)(1925 -2225);
WIRE 16 -1 (1925 -2225)(1925 -2575);
WIRE 16 -1 (-1475 -1750)(-1150 -1750);
WIRE 16 -1 (-1475 -1675)(-1475 -1750);
WIRE 16 -1 (-1475 -1825)(-1475 -1750);
WIRE 16 -1 (-1150 -1675)(-1475 -1675);
WIRE 16 -1 (-2450 -2850)(-375 -2850);
WIRE 16 -1 (-2450 -2850)(-2450 -2375);
WIRE 16 -1 (-2250 -2375)(-2450 -2375);
WIRE 16 -1 (-2450 -2375)(-2750 -2375);
WIRE 16 -1 (-2750 -2375)(-2750 -2275);
WIRE 16 -1 (-1725 -4725)(-250 -4725);
WIRE 16 -1 (-1725 -4725)(-1725 -4525);
WIRE 16 -1 (-1550 -4525)(-1725 -4525);
WIRE 16 -1 (-1725 -4525)(-1950 -4525);
WIRE 16 -1 (-1550 -4525)(-1550 -4425);
WIRE 16 -1 (-2025 -275)(-1850 -275);
WIRE 16 -1 (-2025 -750)(-2025 -275);
WIRE 16 -1 (-2025 -275)(-2325 -275);
WIRE 16 -1 (-2325 -275)(-2325 -175);
WIRE 16 -1 (-2025 -750)(50 -750);
WIRE 16 -1 (-1425 -475)(50 -475);
WIRE 16 -1 (-1425 -475)(-1425 -275);
WIRE 16 -1 (-1425 -275)(-1250 -275);
WIRE 16 -1 (-1425 -275)(-1650 -275);
WIRE 16 -1 (-1250 -275)(-1250 -175);
WIRE 16 -1 (2225 -75)(2350 -75);
WIRE 16 -1 (2350 -75)(2350 -125);
WIRE 16 -1 (2225 -125)(2350 -125);
WIRE 16 -1 (2350 -125)(2350 -475);
WIRE 16 -1 (-625 600)(-950 600);
WIRE 16 -1 (-950 600)(-950 525);
WIRE 16 -1 (-950 525)(-625 525);
WIRE 16 -1 (-950 450)(-950 525);
WIRE 16 -1 (925 225)(1325 225);
WIRE 16 -1 (925 525)(925 225);
WIRE 16 -1 (525 525)(925 525);
WIRE 16 -1 (525 450)(525 525);
WIRE 16 -1 (-425 525)(525 525);
FORCEPROP 2 LAST SIG_NAME INA230_3_A0
J 0
(365 535);
DISPLAY 0.638298 (365 535);
PAINT WHITE (365 535);
FORCEPROP 2 LASTPROP $XRERR UNIQUE?
J 0
(125 535);
DISPLAY 0.638298 (125 535);
PAINT MONO (125 535);
DISPLAY INVISIBLE (125 535);
WIRE 16 -1 (500 -525)(500 -475);
WIRE 16 -1 (1100 -475)(500 -475);
FORCEPROP 2 LAST SIG_NAME VSENSE_P12V_INA230_3_INP
J 0
(515 -465);
DISPLAY 0.510638 (515 -465);
PAINT WHITE (515 -465);
FORCEPROP 2 LASTPROP $XRERR UNIQUE?
J 0
(275 -465);
DISPLAY 0.638298 (275 -465);
PAINT MONO (275 -465);
DISPLAY INVISIBLE (275 -465);
WIRE 16 -1 (500 -475)(250 -475);
WIRE 16 -1 (1100 -475)(1100 -75);
WIRE 16 -1 (1100 -75)(1325 -75);
WIRE 16 -1 (1800 -1825)(2425 -1825);
FORCEPROP 2 LAST SIG_NAME NC_INA230_4_NC0
J 0
(1940 -1815);
DISPLAY 0.638298 (1940 -1815);
PAINT WHITE (1940 -1815);
FORCEPROP 2 LASTPROP $XRERR UNIQUE?
J 0
(2455 -1825);
DISPLAY 0.638298 (2455 -1825);
PAINT MONO (2455 -1825);
DISPLAY INVISIBLE (2455 -1825);
WIRE 16 -1 (1800 -1925)(2425 -1925);
FORCEPROP 2 LAST SIG_NAME NC_INA230_4_NC2
J 0
(1940 -1915);
DISPLAY 0.638298 (1940 -1915);
PAINT WHITE (1940 -1915);
FORCEPROP 2 LASTPROP $XRERR UNIQUE?
J 0
(2455 -1925);
DISPLAY 0.638298 (2455 -1925);
PAINT MONO (2455 -1925);
DISPLAY INVISIBLE (2455 -1925);
WIRE 16 -1 (1925 -4075)(2550 -4075);
FORCEPROP 2 LAST SIG_NAME NC_INA230_5_NC2
J 0
(2065 -4065);
DISPLAY 0.638298 (2065 -4065);
PAINT WHITE (2065 -4065);
FORCEPROP 2 LASTPROP $XRERR UNIQUE?
J 0
(2580 -4075);
DISPLAY 0.638298 (2580 -4075);
PAINT MONO (2580 -4075);
DISPLAY INVISIBLE (2580 -4075);
WIRE 16 -1 (-875 -3850)(125 -3850);
WIRE 16 -1 (925 -3850)(125 -3850);
FORCEPROP 2 LAST SIG_NAME INA230_5_A1
J 0
(315 -3840);
DISPLAY 0.638298 (315 -3840);
PAINT WHITE (315 -3840);
FORCEPROP 2 LASTPROP $XRERR UNIQUE?
J 0
(75 -3840);
DISPLAY 0.638298 (75 -3840);
PAINT MONO (75 -3840);
DISPLAY INVISIBLE (75 -3840);
WIRE 16 -1 (125 -3625)(125 -3850);
WIRE 16 -1 (925 -3850)(925 -3975);
WIRE 16 -1 (925 -3975)(1025 -3975);
WIRE 16 -1 (1800 -2075)(2425 -2075);
FORCEPROP 2 LAST SIG_NAME NC_INA230_4_NC5
J 0
(1940 -2065);
DISPLAY 0.638298 (1940 -2065);
PAINT WHITE (1940 -2065);
FORCEPROP 2 LASTPROP $XRERR UNIQUE?
J 0
(2455 -2075);
DISPLAY 0.638298 (2455 -2075);
PAINT MONO (2455 -2075);
DISPLAY INVISIBLE (2455 -2075);
WIRE 16 -1 (-200 -2025)(900 -2025);
FORCEPROP 2 LAST SIG_NAME SMB_INA230_4_3V3AUX_SDA_R1
J 0
(115 -2015);
DISPLAY 0.680851 (115 -2015);
PAINT WHITE (115 -2015);
FORCEPROP 2 LASTPROP $XRERR UNIQUE?
J 0
(-125 -2015);
DISPLAY 0.638298 (-125 -2015);
PAINT MONO (-125 -2015);
DISPLAY INVISIBLE (-125 -2015);
WIRE 16 -1 (1925 -3975)(2550 -3975);
FORCEPROP 2 LAST SIG_NAME NC_INA230_5_NC0
J 0
(2065 -3965);
DISPLAY 0.638298 (2065 -3965);
PAINT WHITE (2065 -3965);
FORCEPROP 2 LASTPROP $XRERR UNIQUE?
J 0
(2580 -3975);
DISPLAY 0.638298 (2580 -3975);
PAINT MONO (2580 -3975);
DISPLAY INVISIBLE (2580 -3975);
WIRE 16 -1 (-50 -5000)(200 -5000);
WIRE 16 -1 (900 -5000)(200 -5000);
FORCEPROP 2 LAST SIG_NAME VSENSE_P12V_INA230_5_INN
J 0
(240 -4990);
DISPLAY 0.510638 (240 -4990);
PAINT WHITE (240 -4990);
FORCEPROP 2 LASTPROP $XRERR UNIQUE?
J 0
(0 -4990);
DISPLAY 0.638298 (0 -4990);
PAINT MONO (0 -4990);
DISPLAY INVISIBLE (0 -4990);
WIRE 16 -1 (200 -4975)(200 -5000);
WIRE 16 -1 (900 -5000)(900 -4375);
WIRE 16 -1 (900 -4375)(1025 -4375);
WIRE 16 -1 (800 -4725)(800 -4325);
WIRE 16 -1 (800 -4725)(200 -4725);
FORCEPROP 2 LAST SIG_NAME VSENSE_P12V_INA230_5_INP
J 0
(215 -4715);
DISPLAY 0.510638 (215 -4715);
PAINT WHITE (215 -4715);
FORCEPROP 2 LASTPROP $XRERR UNIQUE?
J 0
(-25 -4715);
DISPLAY 0.638298 (-25 -4715);
PAINT MONO (-25 -4715);
DISPLAY INVISIBLE (-25 -4715);
WIRE 16 -1 (800 -4325)(1025 -4325);
WIRE 16 -1 (200 -4775)(200 -4725);
WIRE 16 -1 (200 -4725)(-50 -4725);
WIRE 16 -1 (-875 -3925)(-175 -3925);
WIRE 16 -1 (875 -3925)(-175 -3925);
FORCEPROP 2 LAST SIG_NAME INA230_5_A0
J 0
(315 -3915);
DISPLAY 0.638298 (315 -3915);
PAINT WHITE (315 -3915);
FORCEPROP 2 LASTPROP $XRERR UNIQUE?
J 0
(75 -3915);
DISPLAY 0.638298 (75 -3915);
PAINT MONO (75 -3915);
DISPLAY INVISIBLE (75 -3915);
WIRE 16 -1 (-175 -3625)(-175 -3925);
WIRE 16 -1 (875 -3925)(875 -4025);
WIRE 16 -1 (875 -4025)(1025 -4025);
WIRE 16 -1 (1800 -1875)(2425 -1875);
FORCEPROP 2 LAST SIG_NAME NC_INA230_4_NC1
J 0
(1940 -1865);
DISPLAY 0.638298 (1940 -1865);
PAINT WHITE (1940 -1865);
FORCEPROP 2 LASTPROP $XRERR UNIQUE?
J 0
(2455 -1875);
DISPLAY 0.638298 (2455 -1875);
PAINT MONO (2455 -1875);
DISPLAY INVISIBLE (2455 -1875);
WIRE 16 -1 (3025 -3875)(4050 -3875);
FORCEPROP 2 LAST SIG_NAME P12V_SCM_ADC_ALERT
J 0
(3415 -3865);
DISPLAY 0.638298 (3415 -3865);
PAINT WHITE (3415 -3865);
WIRE 16 -1 (2225 125)(2850 125);
FORCEPROP 2 LAST SIG_NAME NC_INA230_3_NC3
J 0
(2365 135);
DISPLAY 0.638298 (2365 135);
PAINT WHITE (2365 135);
FORCEPROP 2 LASTPROP $XRERR UNIQUE?
J 0
(2880 125);
DISPLAY 0.638298 (2880 125);
PAINT MONO (2880 125);
DISPLAY INVISIBLE (2880 125);
WIRE 16 -1 (1800 -1975)(2425 -1975);
FORCEPROP 2 LAST SIG_NAME NC_INA230_4_NC3
J 0
(1940 -1965);
DISPLAY 0.638298 (1940 -1965);
PAINT WHITE (1940 -1965);
FORCEPROP 2 LASTPROP $XRERR UNIQUE?
J 0
(2455 -1975);
DISPLAY 0.638298 (2455 -1975);
PAINT MONO (2455 -1975);
DISPLAY INVISIBLE (2455 -1975);
WIRE 16 -1 (1925 -4025)(2550 -4025);
FORCEPROP 2 LAST SIG_NAME NC_INA230_5_NC1
J 0
(2065 -4015);
DISPLAY 0.638298 (2065 -4015);
PAINT WHITE (2065 -4015);
FORCEPROP 2 LASTPROP $XRERR UNIQUE?
J 0
(2580 -4025);
DISPLAY 0.638298 (2580 -4025);
PAINT MONO (2580 -4025);
DISPLAY INVISIBLE (2580 -4025);
WIRE 16 -1 (1800 -2025)(2425 -2025);
FORCEPROP 2 LAST SIG_NAME NC_INA230_4_NC4
J 0
(1940 -2015);
DISPLAY 0.638298 (1940 -2015);
PAINT WHITE (1940 -2015);
FORCEPROP 2 LASTPROP $XRERR UNIQUE?
J 0
(2455 -2025);
DISPLAY 0.638298 (2455 -2025);
PAINT MONO (2455 -2025);
DISPLAY INVISIBLE (2455 -2025);
WIRE 16 -1 (2225 25)(2850 25);
FORCEPROP 2 LAST SIG_NAME NC_INA230_3_NC5
J 0
(2365 35);
DISPLAY 0.638298 (2365 35);
PAINT WHITE (2365 35);
FORCEPROP 2 LASTPROP $XRERR UNIQUE?
J 0
(2880 25);
DISPLAY 0.638298 (2880 25);
PAINT MONO (2880 25);
DISPLAY INVISIBLE (2880 25);
WIRE 16 -1 (2225 175)(2850 175);
FORCEPROP 2 LAST SIG_NAME NC_INA230_3_NC2
J 0
(2365 185);
DISPLAY 0.638298 (2365 185);
PAINT WHITE (2365 185);
FORCEPROP 2 LASTPROP $XRERR UNIQUE?
J 0
(2880 175);
DISPLAY 0.638298 (2880 175);
PAINT MONO (2880 175);
DISPLAY INVISIBLE (2880 175);
WIRE 16 -1 (2225 75)(2850 75);
FORCEPROP 2 LAST SIG_NAME NC_INA230_3_NC4
J 0
(2365 85);
DISPLAY 0.638298 (2365 85);
PAINT WHITE (2365 85);
FORCEPROP 2 LASTPROP $XRERR UNIQUE?
J 0
(2880 75);
DISPLAY 0.638298 (2880 75);
PAINT MONO (2880 75);
DISPLAY INVISIBLE (2880 75);
WIRE 16 -1 (-1025 125)(0 125);
FORCEPROP 2 LAST SIG_NAME SMB_INA230_3_3V3AUX_SCL_R
J 0
(-1035 135);
DISPLAY 0.680851 (-1035 135);
PAINT WHITE (-1035 135);
WIRE 16 -1 (-1450 -1975)(-400 -1975);
FORCEPROP 2 LAST SIG_NAME SMB_INA230_4_3V3AUX_SCL_R
J 0
(-1385 -1965);
DISPLAY 0.680851 (-1385 -1965);
PAINT WHITE (-1385 -1965);
WIRE 16 -1 (-1450 -2025)(-400 -2025);
FORCEPROP 2 LAST SIG_NAME SMB_INA230_4_3V3AUX_SDA_R
J 0
(-1385 -2015);
DISPLAY 0.680851 (-1385 -2015);
PAINT WHITE (-1385 -2015);
WIRE 16 -1 (200 75)(1325 75);
FORCEPROP 2 LAST SIG_NAME SMB_INA230_3_3V3AUX_SDA_R1
J 0
(515 85);
DISPLAY 0.680851 (515 85);
PAINT WHITE (515 85);
FORCEPROP 2 LASTPROP $XRERR UNIQUE?
J 0
(275 85);
DISPLAY 0.638298 (275 85);
PAINT MONO (275 85);
DISPLAY INVISIBLE (275 85);
WIRE 16 -1 (-75 -4175)(1025 -4175);
FORCEPROP 2 LAST SIG_NAME SMB_INA230_5_3V3AUX_SDA_R1
J 0
(240 -4165);
DISPLAY 0.680851 (240 -4165);
PAINT WHITE (240 -4165);
FORCEPROP 2 LASTPROP $XRERR UNIQUE?
J 0
(0 -4165);
DISPLAY 0.638298 (0 -4165);
PAINT MONO (0 -4165);
DISPLAY INVISIBLE (0 -4165);
WIRE 16 -1 (-75 -4125)(1025 -4125);
FORCEPROP 2 LAST SIG_NAME SMB_INA230_5_3V3AUX_SCL_R1
J 0
(240 -4115);
DISPLAY 0.680851 (240 -4115);
PAINT WHITE (240 -4115);
FORCEPROP 2 LASTPROP $XRERR UNIQUE?
J 0
(0 -4115);
DISPLAY 0.638298 (0 -4115);
PAINT MONO (0 -4115);
DISPLAY INVISIBLE (0 -4115);
WIRE 16 -1 (-1325 -4125)(-275 -4125);
FORCEPROP 2 LAST SIG_NAME SMB_INA230_5_3V3AUX_SCL_R
J 0
(-1260 -4115);
DISPLAY 0.680851 (-1260 -4115);
PAINT WHITE (-1260 -4115);
WIRE 16 -1 (200 125)(525 125);
WIRE 16 -1 (525 125)(1325 125);
FORCEPROP 2 LAST SIG_NAME SMB_INA230_3_3V3AUX_SCL_R1
J 0
(540 135);
DISPLAY 0.680851 (540 135);
PAINT WHITE (540 135);
FORCEPROP 2 LASTPROP $XRERR UNIQUE?
J 0
(300 135);
DISPLAY 0.638298 (300 135);
PAINT MONO (300 135);
DISPLAY INVISIBLE (300 135);
WIRE 16 -1 (525 250)(525 125);
WIRE 16 -1 (250 -750)(500 -750);
WIRE 16 -1 (1200 -750)(500 -750);
FORCEPROP 2 LAST SIG_NAME VSENSE_P12V_INA230_3_INN
J 0
(540 -740);
DISPLAY 0.510638 (540 -740);
PAINT WHITE (540 -740);
FORCEPROP 2 LASTPROP $XRERR UNIQUE?
J 0
(300 -740);
DISPLAY 0.638298 (300 -740);
PAINT MONO (300 -740);
DISPLAY INVISIBLE (300 -740);
WIRE 16 -1 (500 -725)(500 -750);
WIRE 16 -1 (1200 -750)(1200 -125);
WIRE 16 -1 (1200 -125)(1325 -125);
WIRE 16 -1 (1000 275)(1325 275);
WIRE 16 -1 (1000 600)(1000 275);
WIRE 16 -1 (-425 600)(1000 600);
FORCEPROP 2 LAST SIG_NAME INA230_3_A1
J 0
(390 610);
DISPLAY 0.638298 (390 610);
PAINT WHITE (390 610);
FORCEPROP 2 LASTPROP $XRERR UNIQUE?
J 0
(150 610);
DISPLAY 0.638298 (150 610);
PAINT MONO (150 610);
DISPLAY INVISIBLE (150 610);
WIRE 16 -1 (-200 -1975)(900 -1975);
FORCEPROP 2 LAST SIG_NAME SMB_INA230_4_3V3AUX_SCL_R1
J 0
(115 -1965);
DISPLAY 0.680851 (115 -1965);
PAINT WHITE (115 -1965);
FORCEPROP 2 LASTPROP $XRERR UNIQUE?
J 0
(-125 -1965);
DISPLAY 0.638298 (-125 -1965);
PAINT MONO (-125 -1965);
DISPLAY INVISIBLE (-125 -1965);
WIRE 16 -1 (750 -1875)(900 -1875);
WIRE 16 -1 (750 -1750)(750 -1875);
WIRE 16 -1 (-225 -1750)(750 -1750);
FORCEPROP 2 LAST SIG_NAME INA230_4_A0
J 0
(190 -1740);
DISPLAY 0.638298 (190 -1740);
PAINT WHITE (190 -1740);
FORCEPROP 2 LASTPROP $XRERR UNIQUE?
J 0
(-50 -1740);
DISPLAY 0.638298 (-50 -1740);
PAINT MONO (-50 -1740);
DISPLAY INVISIBLE (-50 -1740);
WIRE 16 -1 (-225 -1425)(-225 -1750);
WIRE 16 -1 (-950 -1750)(-225 -1750);
WIRE 16 -1 (-1025 75)(0 75);
FORCEPROP 2 LAST SIG_NAME SMB_INA230_3_3V3AUX_SDA_R
J 0
(-1035 85);
DISPLAY 0.680851 (-1035 85);
PAINT WHITE (-1035 85);
WIRE 16 -1 (-1650 400)(-1650 525);
WIRE 16 -1 (-1650 525)(-1400 525);
WIRE 16 -1 (-1400 575)(-1400 525);
WIRE 16 -1 (-1400 525)(-1400 -25);
WIRE 16 -1 (1325 -25)(-1400 -25);
WIRE 16 -1 (800 -1675)(800 -1825);
WIRE 16 -1 (75 -1675)(800 -1675);
FORCEPROP 2 LAST SIG_NAME INA230_4_A1
J 0
(190 -1665);
DISPLAY 0.638298 (190 -1665);
PAINT WHITE (190 -1665);
FORCEPROP 2 LASTPROP $XRERR UNIQUE?
J 0
(-50 -1665);
DISPLAY 0.638298 (-50 -1665);
PAINT MONO (-50 -1665);
DISPLAY INVISIBLE (-50 -1665);
WIRE 16 -1 (800 -1825)(900 -1825);
WIRE 16 -1 (75 -1425)(75 -1675);
WIRE 16 -1 (-950 -1675)(75 -1675);
WIRE 16 -1 (675 -2575)(675 -2175);
WIRE 16 -1 (675 -2575)(75 -2575);
FORCEPROP 2 LAST SIG_NAME VSENSE_P12V_INA230_4_INP
J 0
(90 -2565);
DISPLAY 0.510638 (90 -2565);
PAINT WHITE (90 -2565);
FORCEPROP 2 LASTPROP $XRERR UNIQUE?
J 0
(-150 -2565);
DISPLAY 0.638298 (-150 -2565);
PAINT MONO (-150 -2565);
DISPLAY INVISIBLE (-150 -2565);
WIRE 16 -1 (675 -2175)(900 -2175);
WIRE 16 -1 (75 -2625)(75 -2575);
WIRE 16 -1 (75 -2575)(-175 -2575);
WIRE 16 -1 (-1850 -2575)(-375 -2575);
WIRE 16 -1 (-1850 -2575)(-1850 -2375);
WIRE 16 -1 (-1675 -2375)(-1850 -2375);
WIRE 16 -1 (-1850 -2375)(-2050 -2375);
WIRE 16 -1 (-1675 -2375)(-1675 -2275);
WIRE 16 -1 (1925 -4125)(2550 -4125);
FORCEPROP 2 LAST SIG_NAME NC_INA230_5_NC3
J 0
(2065 -4115);
DISPLAY 0.638298 (2065 -4115);
PAINT WHITE (2065 -4115);
FORCEPROP 2 LASTPROP $XRERR UNIQUE?
J 0
(2580 -4125);
DISPLAY 0.638298 (2580 -4125);
PAINT MONO (2580 -4125);
DISPLAY INVISIBLE (2580 -4125);
WIRE 16 -1 (1925 -4175)(2550 -4175);
FORCEPROP 2 LAST SIG_NAME NC_INA230_5_NC4
J 0
(2065 -4165);
DISPLAY 0.638298 (2065 -4165);
PAINT WHITE (2065 -4165);
FORCEPROP 2 LASTPROP $XRERR UNIQUE?
J 0
(2580 -4175);
DISPLAY 0.638298 (2580 -4175);
PAINT MONO (2580 -4175);
DISPLAY INVISIBLE (2580 -4175);
WIRE 16 -1 (1925 -4225)(2550 -4225);
FORCEPROP 2 LAST SIG_NAME NC_INA230_5_NC5
J 0
(2065 -4215);
DISPLAY 0.638298 (2065 -4215);
PAINT WHITE (2065 -4215);
FORCEPROP 2 LASTPROP $XRERR UNIQUE?
J 0
(2580 -4225);
DISPLAY 0.638298 (2580 -4225);
PAINT MONO (2580 -4225);
DISPLAY INVISIBLE (2580 -4225);
WIRE 16 -1 (1925 -3875)(2675 -3875);
FORCEPROP 2 LAST SIG_NAME P12V_SCM_ADC_ALERT_R
J 0
(2065 -3865);
DISPLAY 0.638298 (2065 -3865);
PAINT WHITE (2065 -3865);
FORCEPROP 2 LASTPROP $XRERR UNIQUE?
J 0
(1825 -3865);
DISPLAY 0.638298 (1825 -3865);
PAINT MONO (1825 -3865);
DISPLAY INVISIBLE (1825 -3865);
WIRE 16 -1 (2675 -3525)(2675 -3875);
WIRE 16 -1 (2675 -3875)(2825 -3875);
WIRE 16 -1 (1800 -1725)(2600 -1725);
FORCEPROP 2 LAST SIG_NAME M2_0_P3V3_ADC_ALERT_R
J 0
(1940 -1715);
DISPLAY 0.638298 (1940 -1715);
PAINT WHITE (1940 -1715);
FORCEPROP 2 LASTPROP $XRERR UNIQUE?
J 0
(1700 -1715);
DISPLAY 0.638298 (1700 -1715);
PAINT MONO (1700 -1715);
DISPLAY INVISIBLE (1700 -1715);
WIRE 16 -1 (2600 -1375)(2600 -1725);
WIRE 16 -1 (2600 -1725)(2700 -1725);
DOT 1 (2675 -3875);
DOT 1 (-175 -3925);
DOT 1 (-225 -1750);
DOT 1 (525 125);
DOT 1 (-1850 -2375);
DOT 1 (975 -3300);
DOT 1 (125 -3350);
DOT 1 (200 -4725);
DOT 1 (200 -5000);
DOT 1 (-1400 -3925);
DOT 1 (-1725 -4525);
DOT 1 (-2325 -4525);
DOT 1 (850 -1150);
DOT 1 (75 -1150);
DOT 1 (75 -1675);
DOT 1 (1925 -2225);
DOT 1 (75 -2575);
DOT 1 (75 -2850);
DOT 1 (-2450 -2375);
DOT 1 (2350 -125);
DOT 1 (1275 950);
DOT 1 (525 525);
DOT 1 (-950 525);
DOT 1 (500 -475);
DOT 1 (500 -750);
DOT 1 (-1400 525);
DOT 1 (-1425 -275);
DOT 1 (-2025 -275);
DOT 1 (-1475 -1750);
DOT 1 (-1825 -1575);
DOT 1 (2050 -4375);
DOT 1 (125 -3850);
DOT 1 (-1700 -3725);
DOT 1 (2600 -1725);
DOT 1 (3175 375);
FORCENOTE
ADDRESS : 0X8A (8-BIT)
(2200 -4675) 0;
DISPLAY LEFT (2200 -4675);
DISPLAY 1.340425 (2200 -4675);
PAINT WHITE (2200 -4675);
FORCENOTE
0X45 (7-BIT)
(2825 -4750) 0;
DISPLAY LEFT (2825 -4750);
DISPLAY 1.276596 (2825 -4750);
PAINT WHITE (2825 -4750);
FORCENOTE
0X44 (7-BIT)
(2750 -2475) 0;
DISPLAY LEFT (2750 -2475);
DISPLAY 1.276596 (2750 -2475);
PAINT WHITE (2750 -2475);
FORCENOTE
ADDRESS : 0X88 (8-BIT)
(2100 -2400) 0;
DISPLAY LEFT (2100 -2400);
DISPLAY 1.340425 (2100 -2400);
PAINT WHITE (2100 -2400);
FORCENOTE
0X43 (7-BIT)
(3100 -275) 0;
DISPLAY LEFT (3100 -275);
DISPLAY 1.276596 (3100 -275);
PAINT WHITE (3100 -275);
FORCENOTE
ADDRESS : 0X86 (8-BIT)
(2450 -200) 0;
DISPLAY LEFT (2450 -200);
DISPLAY 1.340425 (2450 -200);
PAINT WHITE (2450 -200);
QUIT
